G04 ================== begin FILE IDENTIFICATION RECORD ==================*
G04 Layout Name:  12004-1.brd*
G04 Film Name:    L3*
G04 File Format:  Gerber RS274X*
G04 File Origin:  Cadence Allegro 16.2-S033*
G04 Origin Date:  Tue Oct 16 14:36:03 2012*
G04 *
G04 Layer:  VIA CLASS/L3*
G04 Layer:  PIN/L3*
G04 Layer:  ETCH/L3*
G04 Layer:  DRAWING FORMAT/LAYER_PCB_STORY*
G04 Layer:  DRAWING FORMAT/LAYER_L3*
G04 *
G04 Offset:    (0.00 0.00)*
G04 Mirror:    No*
G04 Mode:      Positive*
G04 Rotation:  0*
G04 FullContactRelief:  No*
G04 UndefLineWidth:     6.00*
G04 ================== end FILE IDENTIFICATION RECORD ====================*
%FSLAX35Y35*MOIN*%
%IR0*IPPOS*OFA0.00000B0.00000*MIA0B0*SFA1.00000B1.00000*%
%ADD10C,.01*%
%ADD13C,.02*%
%ADD11C,.022*%
%ADD15C,.05*%
%ADD19C,.061*%
%ADD17C,.055*%
%ADD14C,.046*%
%ADD12C,.028*%
%ADD16C,.213*%
%ADD18C,.115*%
%ADD20C,.012*%
%ADD21C,.03*%
%ADD22C,.04*%
%ADD23C,.025*%
%ADD24C,.006*%
%ADD25C,.0045*%
%ADD35C,.03204*%
%ADD32C,.05204*%
%ADD30C,.07004*%
%ADD34C,.04604*%
%ADD33C,.07404*%
%ADD38C,.08504*%
%ADD29C,.08506*%
%ADD37C,.07904*%
%ADD28C,.08606*%
%ADD27C,.10306*%
%ADD31C,.23704*%
%ADD36C,.13904*%
%ADD26C,.18206*%
G75*
%LPD*%
G75*
G36*
G01X5000Y3400D02*
X3500Y4900D01*
Y211400D01*
X-900Y215800D01*
X-139900D01*
X-140600Y216500D01*
Y338800D01*
X-140100Y339300D01*
X-62100D01*
X-60300Y340000D01*
X-58600Y340800D01*
X-56900Y342600D01*
X-56000Y344900D01*
Y504100D01*
X-55300Y504800D01*
X-3400D01*
X-1500Y505100D01*
X700Y506400D01*
X2300Y508400D01*
X3100Y510900D01*
Y542800D01*
X4000Y543700D01*
Y550331D01*
G02X4627Y550660I400J0D01*
G03Y556428I1987J2884D01*
G02X4000Y556757I-227J329D01*
G01Y668441D01*
G02X4627Y668770I400J0D01*
G03Y674538I1987J2884D01*
G02X4000Y674867I-227J329D01*
G01Y782400D01*
X5400Y783800D01*
X78600D01*
X82100Y787300D01*
Y921000D01*
X82900Y921800D01*
X755100D01*
X756300Y920600D01*
Y825300D01*
X755202Y824202D01*
X747862D01*
X735354Y836709D01*
X735345Y836775D01*
G03X732741Y834171I-2279J-325D01*
G01X732807Y834162D01*
X746370Y820598D01*
X750633D01*
G02X750916Y819916I0J-400D01*
G01X750600Y819600D01*
X693651D01*
G02X693270Y820120I1J400D01*
G03X688880I-2195J694D01*
G02X688499Y819600I-382J-120D01*
G01X661300D01*
X660600Y820300D01*
Y821700D01*
X676800Y837900D01*
X681500D01*
X695800Y852200D01*
X711300D01*
X715800Y847700D01*
X724000D01*
X724900Y848600D01*
Y850600D01*
X722500Y853000D01*
X721595D01*
X721580Y853002D01*
G03X721077Y853021I-338J-2277D01*
G01X720986Y853014D01*
X719800Y854200D01*
Y860700D01*
X721500Y862400D01*
Y864300D01*
X719200Y866600D01*
X622800D01*
X330600Y574400D01*
X324100D01*
X297300Y547600D01*
X262100D01*
X234100Y575600D01*
Y637036D01*
G02X234783Y637319I400J0D01*
G01X278895Y593207D01*
X278888Y593115D01*
G03X281004Y595231I2295J-179D01*
G01X280912Y595224D01*
X234100Y642036D01*
Y751800D01*
X225600Y760300D01*
Y770400D01*
X242800Y787600D01*
Y793300D01*
X238200Y797900D01*
X236100D01*
X228700Y790500D01*
Y790023D01*
G02X228259Y789625I-400J0D01*
G03Y785045I-238J-2290D01*
G02X228700Y784647I41J-398D01*
G01Y783200D01*
X208200Y762700D01*
Y662400D01*
X204562Y658762D01*
X87300Y776025D01*
X87294Y776097D01*
G03X85504Y773654I-2294J-197D01*
G01X85612Y773678D01*
X204500Y654790D01*
Y633298D01*
G02X203817Y633015I-400J0D01*
G01X87506Y749326D01*
X86709D01*
X86649Y749396D01*
G03X86391Y746146I-1749J-1496D01*
G01X86532Y746266D01*
X204500Y628298D01*
Y558600D01*
X199000Y553100D01*
X186300D01*
X183139Y556261D01*
G02X183354Y556938I283J283D01*
G03X178787Y561505I-673J3894D01*
G02X178110Y561290I-394J68D01*
G01X93200Y646200D01*
Y657600D01*
X88400Y662400D01*
X84500D01*
X83300Y661200D01*
Y656700D01*
X83437Y656563D01*
G02X83206Y655883I-282J-283D01*
G03X85783Y653306I294J-2283D01*
G02X86463Y653537I397J-51D01*
G01X88400Y651600D01*
Y645000D01*
X85105Y641705D01*
X84964Y641820D01*
G03X81724Y638580I-1464J-1776D01*
G01X81839Y638439D01*
X79700Y636300D01*
Y630700D01*
X81200Y629200D01*
X97500D01*
X155100Y571600D01*
Y545100D01*
X149000Y539000D01*
X65900D01*
X63700Y536800D01*
Y533300D01*
X62300Y531900D01*
X53200D01*
X49000Y527700D01*
X42600D01*
X41900Y527000D01*
Y515800D01*
X42500Y515200D01*
X48791D01*
G02X49175Y514687I0J-400D01*
G03X53591I2208J-650D01*
G02X53975Y515200I384J113D01*
G01X69900D01*
X70900Y514200D01*
Y510400D01*
X69500Y509000D01*
X60100D01*
X57200Y506100D01*
Y503000D01*
X58700Y501500D01*
Y487047D01*
X58566Y487000D01*
G03Y484166I497J-1417D01*
G01X58700Y484119D01*
Y483305D01*
X58674Y483259D01*
G03Y481775I1306J-742D01*
G01X58700Y481729D01*
Y476300D01*
X56750Y474350D01*
X53950D01*
X52400Y475900D01*
X50300D01*
X47800Y473400D01*
X30500D01*
X28800Y475100D01*
X23400D01*
X1100Y452800D01*
Y307300D01*
X53321Y255079D01*
X53326Y255002D01*
G03X55494Y252834I2298J130D01*
G01X55571Y252829D01*
X58670Y249730D01*
G02X58516Y249069I-283J-282D01*
G03X61437Y246148I742J-2179D01*
G02X62098Y246302I379J-129D01*
G01X79565Y228835D01*
G02X79359Y228159I-283J-283D01*
G03X81903Y226837I441J-2259D01*
G02X82268Y227400I365J163D01*
G01X88636D01*
G02X88958Y226763I0J-400D01*
G03X92286Y227169I1855J-1363D01*
G02X92259Y227759I256J307D01*
G01X96800Y232300D01*
X158483D01*
X158540Y232249D01*
G03X161468I1464J1645D01*
G01X161525Y232300D01*
X164800D01*
X181504Y249004D01*
X181614Y248976D01*
G03X184409Y251771I563J2232D01*
G01X184381Y251881D01*
X184800Y252300D01*
X199200D01*
X199700Y251800D01*
Y237900D01*
X147200Y185400D01*
X141900D01*
X138222Y181722D01*
X138081Y181856D01*
G03X134403Y178178I-1790J-1888D01*
G01X134537Y178037D01*
X129974Y173474D01*
G02X129292Y173722I-283J283D01*
G03X126478Y170908I-2592J-222D01*
G02X126726Y170226I-35J-399D01*
G01X126700Y170200D01*
Y151817D01*
X89859Y114976D01*
X60657D01*
X60581Y114900D01*
X60500D01*
X46200Y100600D01*
X33851D01*
X33791Y100678D01*
G03X27917I-2937J-2253D01*
G01X27857Y100600D01*
X25977D01*
X25917Y100678D01*
G03X19522Y99747I-2937J-2253D01*
G01X19507Y99707D01*
X19200Y99400D01*
Y57500D01*
X23300Y53400D01*
X35000D01*
X42447Y60847D01*
G02X43126Y60622I283J-283D01*
G03X45922Y63592I2574J378D01*
G02X45674Y64274I35J399D01*
G01X47719Y66319D01*
G02X48334Y66258I282J-283D01*
G03X51942Y69866I2166J1442D01*
G02X51881Y70481I222J333D01*
G01X67049Y85649D01*
X67171Y85603D01*
G03X70147Y88579I829J2147D01*
G01X70101Y88701D01*
X72000Y90600D01*
X77478D01*
X77532Y90488D01*
G03X81668I2068J1012D01*
G01X81722Y90600D01*
X90400D01*
X104089Y104289D01*
G02X104658Y104287I284J-282D01*
G03X107913Y107542I1642J1613D01*
G02X107911Y108111I280J285D01*
G01X138750Y138950D01*
Y140699D01*
X142194Y144142D01*
Y159794D01*
X160950Y178550D01*
G02X161576Y178473I283J-283D01*
G03X164734Y181631I1974J1184D01*
G02X164657Y182257I206J343D01*
G01X225450Y243050D01*
Y288550D01*
X252901Y316001D01*
G02X253584Y315718I283J-283D01*
G01Y243373D01*
X233716Y223505D01*
G02X233125Y223533I-283J283D01*
G03X229884Y220292I-1775J-1466D01*
G02X229912Y219701I-255J-308D01*
G01X223400Y213189D01*
X223308Y213196D01*
G03X221705Y212710I-179J-2295D01*
G02X221432Y212733I-124J157D01*
G03X221141Y209389I-1715J-1535D01*
G02X221414Y209366I124J-157D01*
G03X225424Y211080I1715J1535D01*
G01X225417Y211172D01*
X256436Y242191D01*
Y365815D01*
X256506Y365875D01*
G03X256013Y369696I-1496J1749D01*
G01X255900Y369751D01*
Y370400D01*
X254270Y372030D01*
Y372247D01*
X234400Y392117D01*
Y398800D01*
X235944Y400344D01*
X262254Y374033D01*
Y218694D01*
X220367Y176806D01*
X220250Y176843D01*
G03X221314Y173175I-702J-2192D01*
G02X221966Y173122I307J-256D01*
G03X225963Y175405I1982J1170D01*
G01X225890Y175537D01*
X267058Y216704D01*
Y376023D01*
X241050Y402030D01*
Y403810D01*
X241118Y403870D01*
G03Y407330I-1518J1730D01*
G01X241050Y407390D01*
Y429850D01*
X247800Y436600D01*
X254100D01*
X255950Y434750D01*
Y423950D01*
X255150Y423150D01*
Y422320D01*
X255129Y422278D01*
G03Y420204I2055J-1037D01*
G01X255150Y420162D01*
Y403850D01*
X255179Y403821D01*
X255155Y403714D01*
G03X257908Y400961I2245J-508D01*
G01X258015Y400985D01*
X259200Y399800D01*
X263200D01*
X265800Y402400D01*
Y406200D01*
X269700Y410100D01*
X272100D01*
X274500Y407700D01*
Y395600D01*
X267500Y388600D01*
Y384900D01*
X269000Y383400D01*
X270900D01*
X272128Y382172D01*
Y174445D01*
X206075Y108392D01*
X205944Y108463D01*
G03X203269Y108112I-1095J-2025D01*
G02X202734Y108099I-275J291D01*
G03X202817Y104676I-1497J-1749D01*
G02X203352Y104689I275J-291D01*
G03X206598Y104942I1497J1749D01*
G01X206658Y105012D01*
X206729D01*
X274980Y173263D01*
Y382280D01*
X275000Y382300D01*
Y384700D01*
X317400Y427100D01*
G02X318019Y427034I283J-283D01*
G03X322129Y430195I2188J1408D01*
G02X322124Y430728I296J269D01*
G03X322767Y432389I-1958J1713D01*
G01X322769Y432469D01*
X325300Y435000D01*
Y439500D01*
X340250Y454450D01*
X344467D01*
X348986Y458969D01*
Y461561D01*
X620625Y733200D01*
X666638D01*
G02X666986Y732602I0J-400D01*
G03X667491Y729716I2001J-1137D01*
G01X667560Y729656D01*
Y632867D01*
X495852Y461159D01*
Y384360D01*
X495783Y384300D01*
G03X498775I1496J-1749D01*
G01X498706Y384360D01*
Y399289D01*
G02X499282Y399648I400J0D01*
G03Y403782I1013J2067D01*
G02X498706Y404141I-176J359D01*
G01Y408703D01*
G02X499203Y409091I400J0D01*
G03Y413557I561J2233D01*
G02X498706Y413945I-97J388D01*
G01Y459977D01*
X670414Y631685D01*
Y729656D01*
X670483Y729716D01*
G03X670988Y732602I-1496J1749D01*
G02X671336Y733200I348J198D01*
G01X753800D01*
X756200Y730800D01*
Y661500D01*
X760700Y657000D01*
X771100D01*
X772700Y655400D01*
Y384800D01*
X771300Y383400D01*
X763500D01*
X759000Y378900D01*
Y372600D01*
X762700Y368900D01*
X772100D01*
X772600Y368400D01*
Y332400D01*
X771900Y331700D01*
X760000D01*
X756600Y328300D01*
Y5200D01*
X754800Y3400D01*
X5000D01*
G37*
%LPC*%
G75*
G36*
G01X178800Y853600D02*
Y849600D01*
X178300Y849100D01*
X171900D01*
X171400Y849600D01*
Y853500D01*
X171900Y854000D01*
X178400D01*
X178800Y853600D01*
G37*
G36*
G01X168400Y847500D02*
X161800D01*
X160400Y846100D01*
X158300D01*
X157200Y847200D01*
Y852400D01*
X158600Y853800D01*
X160700D01*
X162000Y852500D01*
X168500D01*
X168900Y852100D01*
Y848000D01*
X168400Y847500D01*
G37*
G36*
G01X178800Y844300D02*
Y840100D01*
X178400Y839700D01*
X171800D01*
X171400Y840100D01*
Y844100D01*
X171900Y844600D01*
X178500D01*
X178800Y844300D01*
G37*
G36*
G01X168500Y838100D02*
X161800D01*
X160400Y836700D01*
X158400D01*
X157200Y837900D01*
Y843000D01*
X158600Y844400D01*
X160500D01*
X161900Y843000D01*
X168500D01*
X168900Y842600D01*
Y838500D01*
X168500Y838100D01*
G37*
G36*
G01X178800Y834800D02*
Y830700D01*
X178300Y830200D01*
X172000D01*
X171400Y830800D01*
Y834800D01*
X171800Y835200D01*
X178400D01*
X178800Y834800D01*
G37*
G36*
G01X168600Y828700D02*
X162500D01*
X160700Y826900D01*
X158800D01*
X157400Y828300D01*
Y833600D01*
X158500Y834700D01*
X160800D01*
X162000Y833500D01*
X168500D01*
X168900Y833100D01*
Y829000D01*
X168600Y828700D01*
G37*
G36*
G01X178800Y825200D02*
Y821400D01*
X178100Y820700D01*
X172000D01*
X171400Y821300D01*
Y825400D01*
X171700Y825700D01*
X178300D01*
X178800Y825200D01*
G37*
G36*
G01X161900Y818900D02*
Y816600D01*
X160600Y815300D01*
X158600D01*
X156900Y817000D01*
Y821700D01*
X158300Y823100D01*
X160900D01*
X161900Y824100D01*
X168500D01*
X168900Y823700D01*
Y819600D01*
X168500Y819200D01*
X162200D01*
X161900Y818900D01*
G37*
G36*
G01X88800Y731700D02*
Y727500D01*
X88400Y727100D01*
X81700D01*
X81200Y727600D01*
Y731800D01*
X81500Y732100D01*
X88400D01*
X88800Y731700D01*
G37*
G36*
G01X78300Y725500D02*
X72100D01*
X70500Y723900D01*
X68400D01*
X67200Y725100D01*
Y730500D01*
X68300Y731600D01*
X70600D01*
X71800Y730400D01*
X78400D01*
X78800Y730000D01*
Y726000D01*
X78300Y725500D01*
G37*
G36*
G01X88700Y722100D02*
Y718100D01*
X88200Y717600D01*
X81700D01*
X81300Y718000D01*
Y722100D01*
X81700Y722500D01*
X88300D01*
X88700Y722100D01*
G37*
G36*
G01X71900Y715600D02*
Y713900D01*
X70900Y712900D01*
X68500D01*
X67100Y714300D01*
Y719100D01*
X68900Y720900D01*
X78300D01*
X78800Y720400D01*
Y716500D01*
X78300Y716000D01*
X72300D01*
X71900Y715600D01*
G37*
G36*
G01X88700Y696900D02*
Y692900D01*
X88200Y692400D01*
X81800D01*
X81300Y692900D01*
Y696800D01*
X81900Y697400D01*
X88200D01*
X88700Y696900D01*
G37*
G36*
G01X88800Y687400D02*
Y683500D01*
X88200Y682900D01*
X81600D01*
X81200Y683300D01*
Y687500D01*
X81600Y687900D01*
X88300D01*
X88800Y687400D01*
G37*
G36*
G01X71700Y681000D02*
Y680000D01*
X70600Y678900D01*
X68400D01*
X67100Y680200D01*
Y685300D01*
X68400Y686600D01*
X70500D01*
X70800Y686300D01*
X78300D01*
X78900Y685700D01*
Y682000D01*
X78300Y681400D01*
X72100D01*
X71700Y681000D01*
G37*
G36*
G01X88800Y613500D02*
Y609500D01*
X88200Y608900D01*
X81600D01*
X81200Y609300D01*
Y613300D01*
X81900Y614000D01*
X88300D01*
X88800Y613500D01*
G37*
G36*
G01X88700Y604000D02*
Y600000D01*
X88200Y599500D01*
X81700D01*
X81300Y599900D01*
Y604000D01*
X81800Y604500D01*
X88200D01*
X88700Y604000D01*
G37*
G36*
G01Y578800D02*
Y574800D01*
X88200Y574300D01*
X81700D01*
X81300Y574700D01*
Y578700D01*
X81900Y579300D01*
X88200D01*
X88700Y578800D01*
G37*
G36*
G01Y569300D02*
Y565300D01*
X88300Y564900D01*
X81700D01*
X81400Y565200D01*
Y569400D01*
X81800Y569800D01*
X88200D01*
X88700Y569300D01*
G37*
G36*
G01X717305Y28346D02*
X716791Y28322D01*
X716279D01*
X715765Y28346D01*
X715259Y28393D01*
X714746Y28462D01*
X714232Y28558D01*
X713729Y28681D01*
X713244Y28820D01*
X712757Y28984D01*
X712278Y29171D01*
X711807Y29380D01*
X711350Y29608D01*
X710898Y29861D01*
X710457Y30137D01*
X710040Y30427D01*
X709626Y30740D01*
X709237Y31071D01*
X708859Y31414D01*
X708495Y31784D01*
X708148Y32166D01*
X707824Y32566D01*
X707517Y32979D01*
X707231Y33405D01*
X706964Y33841D01*
X706717Y34291D01*
X706486Y34761D01*
X706287Y35237D01*
X706111Y35702D01*
X705945Y36197D01*
X705809Y36702D01*
X705698Y37205D01*
X705612Y37698D01*
X705541Y38207D01*
X705500Y38730D01*
X705482Y39241D01*
X705488Y39754D01*
X705518Y40268D01*
X705571Y40784D01*
X705653Y41293D01*
X705750Y41786D01*
X705875Y42297D01*
X706028Y42792D01*
X706195Y43269D01*
X706386Y43743D01*
X706599Y44217D01*
X706843Y44680D01*
X707095Y45116D01*
X707369Y45547D01*
X707670Y45972D01*
X707983Y46373D01*
X708318Y46768D01*
X708677Y47145D01*
X709043Y47499D01*
X709431Y47839D01*
X709837Y48163D01*
X710247Y48457D01*
X710670Y48741D01*
X711123Y49009D01*
X711575Y49246D01*
X712040Y49471D01*
X712512Y49663D01*
X712992Y49842D01*
X713492Y49996D01*
X713989Y50125D01*
X714485Y50228D01*
X714992Y50316D01*
X715508Y50376D01*
X716023Y50411D01*
X716535Y50423D01*
X717047Y50411D01*
X717562Y50376D01*
X718078Y50316D01*
X718585Y50228D01*
X719081Y50125D01*
X719578Y49996D01*
X720078Y49842D01*
X720558Y49663D01*
X721030Y49471D01*
X721495Y49246D01*
X721947Y49009D01*
X722400Y48741D01*
X722823Y48457D01*
X723233Y48163D01*
X723639Y47839D01*
X724027Y47499D01*
X724393Y47145D01*
X724752Y46768D01*
X725087Y46373D01*
X725400Y45972D01*
X725701Y45547D01*
X725975Y45116D01*
X726227Y44680D01*
X726471Y44217D01*
X726684Y43743D01*
X726875Y43269D01*
X727042Y42792D01*
X727195Y42297D01*
X727320Y41786D01*
X727417Y41293D01*
X727499Y40784D01*
X727552Y40268D01*
X727582Y39754D01*
X727588Y39241D01*
X727570Y38730D01*
X727529Y38207D01*
X727458Y37698D01*
X727372Y37205D01*
X727261Y36702D01*
X727125Y36197D01*
X726959Y35702D01*
X726783Y35237D01*
X726584Y34761D01*
X726353Y34291D01*
X726106Y33841D01*
X725839Y33405D01*
X725553Y32979D01*
X725246Y32566D01*
X724922Y32166D01*
X724575Y31784D01*
X724211Y31414D01*
X723833Y31071D01*
X723444Y30740D01*
X723030Y30427D01*
X722613Y30137D01*
X722172Y29861D01*
X721720Y29608D01*
X721263Y29380D01*
X720792Y29171D01*
X720313Y28984D01*
X719826Y28820D01*
X719341Y28681D01*
X718838Y28558D01*
X718324Y28462D01*
X717811Y28393D01*
X717305Y28346D01*
G37*
G36*
G01X728300Y828600D02*
X723800Y824100D01*
X721300D01*
X719400Y826000D01*
Y838900D01*
X723200Y842700D01*
X724508D01*
X724547Y842850D01*
G02X728362Y840609I2229J-573D01*
G01X728300Y840550D01*
Y838323D01*
X728327Y838277D01*
G02Y835979I-1995J-1149D01*
G01X728300Y835933D01*
Y828600D01*
G37*
G36*
G01X348952Y794966D02*
G03X348323I-314J-247D01*
G02Y797804I-1813J1419D01*
G03X348952I314J247D01*
G02Y794966I1813J-1419D01*
G37*
G36*
G01X63596Y705527D02*
G03X62979Y705521I-306J-258D01*
G02X60133Y709017I-1786J1452D01*
G03X60263Y709620I-184J355D01*
G02X63442Y712897I1803J1431D01*
G03X63712Y712926I119J160D01*
G02X66742Y709510I1735J-1513D01*
G03X66729Y708858I225J-331D01*
G02X63596Y705527I-1372J-1848D01*
G37*
G36*
G01X89169Y710502D02*
G03X89153Y710773I-155J127D01*
G02X92524Y710973I1593J1662D01*
G03X92540Y710702I155J-127D01*
G02X92596Y707434I-1593J-1662D01*
G03X92604Y706868I287J-279D01*
G02X92717Y703677I-1601J-1654D01*
G03X92727Y703399I148J-134D01*
G02X89416Y703278I-1597J-1658D01*
G03X89406Y703556I-148J134D01*
G02X89354Y706820I1597J1658D01*
G03X89346Y707386I-287J279D01*
G02X89169Y710502I1601J1654D01*
G37*
G36*
G01X72400Y690800D02*
X70400Y688800D01*
X68400D01*
X67100Y690100D01*
Y695300D01*
X68400Y696600D01*
X69326D01*
X69332D01*
G02X69616I142J-2197D01*
G01X69622D01*
X70600D01*
X71400Y695800D01*
X78400D01*
X78800Y695400D01*
Y691200D01*
X78400Y690800D01*
X72400D01*
G37*
G36*
G01X45105Y643993D02*
G03X44421Y643951I-329J-227D01*
G02X44611Y646961I-3279J1718D01*
G03X45284Y646834I375J140D01*
G02X45105Y643993I1716J-1534D01*
G37*
G36*
G01X72200Y607400D02*
X70600Y605800D01*
X68600D01*
X67300Y607100D01*
Y611254D01*
Y611261D01*
G02Y611573I2196J156D01*
G01Y611580D01*
Y612700D01*
X68200Y613600D01*
X69207D01*
X69220Y613602D01*
G02X69772I276J-2185D01*
G01X69785Y613600D01*
X70500D01*
X71800Y612300D01*
X78300D01*
X78800Y611800D01*
Y607900D01*
X78300Y607400D01*
X72200D01*
G37*
G36*
G01X70600Y596000D02*
X70002D01*
X69984Y595996D01*
G02X69154I-415J2163D01*
G01X69136Y596000D01*
X68500D01*
X67200Y597300D01*
Y602400D01*
X68500Y603700D01*
X69242D01*
X69258Y603702D01*
G02X69940I341J-2175D01*
G01X69956Y603700D01*
X70800D01*
X71600Y602900D01*
X78400D01*
X78800Y602500D01*
Y598300D01*
X78400Y597900D01*
X72500D01*
X70600Y596000D01*
G37*
G36*
G01X643371Y592188D02*
X692309Y641126D01*
X755791D01*
X755851Y641196D01*
G02Y638204I1749J-1496D01*
G01X755791Y638274D01*
X693491D01*
X645388Y590171D01*
X645395Y590079D01*
G02X643279Y592195I-2295J-179D01*
G01X643371Y592188D01*
G37*
G36*
G01X65429Y590372D02*
G03X64830Y589944I-209J-341D01*
G02X61328Y591199I-2149J-482D01*
G03X61365Y591477I-123J158D01*
G02X64843Y594178I1760J1324D01*
G03X65374Y594093I312J250D01*
G02X68434Y593436I1205J-1843D01*
G03X68691Y593364I169J107D01*
G02X67806Y590201I970J-1977D01*
G03X67549Y590273I-169J-107D01*
G02X65429Y590372I-970J1977D01*
G37*
G36*
G01X89623Y590000D02*
G03X89615Y590283I-145J138D01*
G02X89516Y593392I1508J1604D01*
G03X89522Y593659I-146J137D01*
G02X92805Y593582I1676J1428D01*
G03X92799Y593315I146J-137D01*
G02X92723Y590374I-1676J-1428D01*
G03X92731Y590091I145J-138D01*
G02X92717Y586869I-1508J-1604D01*
G03X92694Y586599I135J-147D01*
G02X89393Y586944I-1816J-1414D01*
G03X89427Y587213I-129J153D01*
G02X89623Y590000I1796J1274D01*
G37*
G36*
G01X70500Y571300D02*
X69878D01*
X69860Y571297D01*
G02X69040I-410J2163D01*
G01X69022Y571300D01*
X68400D01*
X67100Y572600D01*
Y577600D01*
X68400Y578900D01*
X70300D01*
X71600Y577600D01*
X78400D01*
X78800Y577200D01*
Y573200D01*
X78300Y572700D01*
X71900D01*
X70500Y571300D01*
G37*
G36*
G01Y562000D02*
X69812D01*
X69801Y561999D01*
G02X69309I-246J2188D01*
G01X69298Y562000D01*
X68500D01*
X67300Y563200D01*
Y568400D01*
X68500Y569600D01*
X70600D01*
X72000Y568200D01*
X78500D01*
X78800Y567900D01*
Y563800D01*
X78300Y563300D01*
X71800D01*
X70500Y562000D01*
G37*
G36*
G01X699867Y558483D02*
G03X699305Y558453I-266J-299D01*
G02X699133Y561717I-1705J1547D01*
G03X699695Y561747I266J299D01*
G02X699867Y558483I1705J-1547D01*
G37*
G36*
G01X744548Y547914D02*
G03X744277Y547896I-126J-155D01*
G02X744059Y551267I-1670J1585D01*
G03X744330Y551285I126J155D01*
G02X744548Y547914I1670J-1585D01*
G37*
G36*
G01X703752Y548737D02*
G03X703692Y548142I234J-324D01*
G02X700648Y548444I-1692J-1561D01*
G03X700708Y549039I-234J324D01*
G02X700951Y552389I1692J1561D01*
G03Y553011I-251J311D01*
G02X703849I1449J1789D01*
G03Y552389I251J-311D01*
G02X703752Y548737I-1449J-1789D01*
G37*
G36*
G01X754779Y533243D02*
G03X754507Y533232I-130J-152D01*
G02X751139Y533341I-1633J1622D01*
G03X750869Y533370I-151J-131D01*
G02X751228Y536729I-1376J1846D01*
G03X751498Y536700I151J131D01*
G02X754367Y536606I1376J-1846D01*
G03X754639Y536617I130J152D01*
G02X754779Y533243I1633J-1622D01*
G37*
G36*
G01X754992Y506278D02*
G03X754356Y506042I-244J-316D01*
G02X749805Y506316I-2256J458D01*
G03X749598Y506500I-199J-16D01*
G02X751795Y508984I-98J2300D01*
G03X752002Y508800I199J16D01*
G02X753508Y508322I99J-2300D01*
G03X754144Y508558I244J316D01*
G02X754992Y506278I2256J-459D01*
G37*
G36*
G01X40766Y492474D02*
G03X40579Y491954I179J-358D01*
G02X35635Y491335I-2379J-1054D01*
G03X35221Y491801I-395J66D01*
G02X36898Y496280I-121J2599D01*
G03X37498Y496334I276J289D01*
G02X40766Y492474I2102J-1534D01*
G37*
G36*
G01X501463Y487963D02*
G03X501238Y487810I-30J-198D01*
G02X499333Y490599I-2244J512D01*
G03X499558Y490752I30J198D01*
G02X501463Y487963I2244J-512D01*
G37*
G36*
G01X504391Y477201D02*
G03X503977Y476860I-18J-400D01*
G02X501809Y479499I-2277J340D01*
G03X502223Y479840I18J400D01*
G02X504391Y477201I2277J-340D01*
G37*
G36*
G01X431500Y478683D02*
G03X431820Y479109I-79J392D01*
G02X432517Y481117I2592J225D01*
G03X432531Y481650I-291J274D01*
G02X437037Y483973I1984J1683D01*
G03X437541Y483689I388J99D01*
G02X437398Y478759I759J-2489D01*
G03X436880Y478511I-139J-375D01*
G02X434926Y476783I-2469J823D01*
G03X434606Y476357I79J-392D01*
G02X431500Y478683I-2592J-225D01*
G37*
G36*
G01X411947Y472271D02*
G03X411944Y471681I268J-296D01*
G02X408432Y471698I-1765J-1912D01*
G03X408435Y472288I-268J296D01*
G02X411947Y472271I1765J1912D01*
G37*
G36*
G01X384195Y469386D02*
G03Y468780I260J-303D01*
G02X381195I-1500J-1747D01*
G03Y469386I-260J303D01*
G02X384195I1500J1747D01*
G37*
G36*
G01X736855Y455680D02*
G03X736851Y455413I147J-136D01*
G02X733567Y455454I-1660J-1446D01*
G03X733571Y455721I-147J136D01*
G02X736855Y455680I1660J1446D01*
G37*
G36*
G01X692100Y479700D02*
Y451000D01*
X694500Y448600D01*
Y448500D01*
X701000Y442000D01*
X713200D01*
X714800Y440400D01*
Y435500D01*
X712700Y433400D01*
X704647D01*
G03X704315Y432778I1J-400D01*
G02X700617Y430044I-1914J-1279D01*
G03X700010Y430059I-310J-253D01*
G02X697789Y433844I-1710J1541D01*
G03X697983Y434517I-89J390D01*
G01X684401Y448099D01*
X684261Y447980D01*
G02X681211Y448047I-1487J1757D01*
G01X681154Y448100D01*
X677952D01*
X677931Y447924D01*
G02X673559I-2186J265D01*
G01X673538Y448100D01*
X673000D01*
X667263Y453837D01*
X667208Y453851D01*
G02X666047Y454535I537J2238D01*
G01X665987Y454600D01*
X661500D01*
X661128Y454972D01*
X661104Y454985D01*
G02X660237Y455852I1062J1929D01*
G01X660224Y455876D01*
X659900Y456200D01*
Y458909D01*
X659872Y458957D01*
G02X659692Y460845I1888J1133D01*
G01X659736Y460964D01*
X658800Y461900D01*
X658300D01*
X658155Y462045D01*
X658078Y462049D01*
G02X655996Y464131I117J2199D01*
G01X655992Y464208D01*
X649602Y470598D01*
X649587Y470608D01*
G02X649171Y470981I1250J1813D01*
G01X649111Y471050D01*
X648326D01*
X648268Y470999D01*
G02X645320I-1474J1635D01*
G01X645262Y471050D01*
X645150D01*
X644200Y472000D01*
Y475146D01*
X644187Y475180D01*
G02Y476742I2059J781D01*
G01X644200Y476776D01*
Y478359D01*
X644187Y478393D01*
G02Y479929I2064J768D01*
G01X644200Y479963D01*
Y480600D01*
X645100Y481500D01*
X646700D01*
X647000Y481800D01*
Y488472D01*
X630722Y504751D01*
Y520400D01*
G02X637124I3201J0D01*
G01Y507403D01*
X653528Y491000D01*
X680800D01*
X685860Y485940D01*
G03X686509Y486062I283J283D01*
G02X689544Y483027I2106J-929D01*
G03X689422Y482378I161J-366D01*
G01X692100Y479700D01*
G37*
G36*
G01X369449Y422715D02*
G03X368830Y422678I-294J-271D01*
G02X368637Y425958I-2111J1521D01*
G03X369256Y425995I294J271D01*
G02X373381Y426120I2111J-1522D01*
G03X374001I310J253D01*
G02X377860Y426308I2014J-1647D01*
G03X378452Y426335I284J282D01*
G02X378613Y422843I2006J-1657D01*
G03X378021Y422816I-284J-282D01*
G02X374001Y422826I-2006J1657D01*
G03X373381I-310J-253D01*
G02X369449Y422715I-2014J1647D01*
G37*
G36*
G01X369383Y414999D02*
G03X368764Y414962I-294J-271D01*
G02X368571Y418242I-2111J1521D01*
G03X369190Y418279I294J271D01*
G02X373315Y418404I2111J-1522D01*
G03X373935I310J253D01*
G02X377794Y418592I2014J-1647D01*
G03X378386Y418619I284J282D01*
G02X378547Y415127I2006J-1657D01*
G03X377955Y415100I-284J-282D01*
G02X373935Y415110I-2006J1657D01*
G03X373315I-310J-253D01*
G02X369383Y414999I-2014J1647D01*
G37*
G36*
G01X369947Y406327D02*
G03X369328Y406290I-294J-271D01*
G02X369135Y409570I-2111J1521D01*
G03X369754Y409607I294J271D01*
G02X373879Y409732I2111J-1522D01*
G03X374499I310J253D01*
G02X378358Y409920I2014J-1647D01*
G03X378950Y409947I284J282D01*
G02X379111Y406455I2006J-1657D01*
G03X378519Y406428I-284J-282D01*
G02X374499Y406438I-2006J1657D01*
G03X373879I-310J-253D01*
G02X369947Y406327I-2014J1647D01*
G37*
G36*
G01X475645Y384249D02*
G03X475666Y383978I157J-124D01*
G02X472299Y383711I-1560J-1693D01*
G03X472278Y383982I-157J124D01*
G02X472046Y387120I1560J1693D01*
G03X472028Y387391I-155J126D01*
G02X475397Y387623I1577J1677D01*
G03X475415Y387352I155J-126D01*
G02X475645Y384249I-1577J-1677D01*
G37*
G36*
G01X187349Y239336D02*
G03X187313Y238803I279J-287D01*
G02X183893Y239030I-1812J-1420D01*
G03X183929Y239563I-279J287D01*
G02X184376Y242837I1811J1420D01*
G03X184350Y243500I-237J323D01*
G02X186927Y243602I1213J1956D01*
G03X186953Y242939I237J-323D01*
G02X187349Y239336I-1213J-1957D01*
G37*
G36*
G01X172905Y234546D02*
G03X173477Y234525I296J269D01*
G02X173359Y231311I1587J-1667D01*
G03X172787Y231332I-296J-269D01*
G02X172905Y234546I-1587J1667D01*
G37*
G36*
G01X135915Y219955D02*
G03X135862Y219302I202J-345D01*
G02X132424Y215398I-1663J-2001D01*
G03X131864Y215385I-273J-292D01*
G02X131776Y219102I-1864J1815D01*
G03X132336Y219115I273J292D01*
G02X132885Y219545I1864J-1815D01*
G03X132938Y220198I-202J345D01*
G02X135915Y219955I1662J2002D01*
G37*
G36*
G01X112598Y205275D02*
G03X112727Y204736I345J-202D01*
G02X109494Y203961I-1245J-1936D01*
G03X109365Y204500I-345J202D01*
G02X112598Y205275I1245J1936D01*
G37*
G36*
G01X28416Y188882D02*
G03X28164Y188319I107J-386D01*
G02X25484Y189518I-2064J-1019D01*
G03X25736Y190081I-107J386D01*
G02X28416Y188882I2064J1019D01*
G37*
G36*
G01X187722Y164655D02*
G03X187816Y165245I-216J337D01*
G02X188002Y168357I1784J1455D01*
G03X188010Y168637I-139J144D01*
G02X188165Y171916I1690J1563D01*
G03X188190Y172186I-133J149D01*
G02X191553Y171870I1828J1400D01*
G03X191528Y171600I133J-149D01*
G02X191298Y168543I-1828J-1400D01*
G03X191290Y168263I139J-144D01*
G02X190839Y164760I-1690J-1563D01*
G03X190745Y164170I216J-337D01*
G02X187722Y164655I-1784J-1455D01*
G37*
G36*
G01X164321Y167235D02*
G03X164713Y167634I-8J400D01*
G02X168642Y169261I2302J-1D01*
G03X169208I283J283D01*
G01X174886Y174939D01*
Y177126D01*
G03X174213Y177419I-400J0D01*
G02X174591Y180333I-1568J1685D01*
G03X175249Y180306I338J214D01*
G02X179297Y178274I1838J-1386D01*
G01X179288Y178247D01*
Y173115D01*
X169005Y162832D01*
X166145D01*
X154552Y151238D01*
Y131757D01*
X154560Y131730D01*
G02X150140I-2210J-646D01*
G01X150148Y131757D01*
Y153062D01*
X164321Y167235D01*
G37*
G36*
G01X207061Y127739D02*
G03X206741Y127259I71J-394D01*
G02X201663Y127276I-2541J-560D01*
G03X201356Y127755I-390J88D01*
G02X203937Y131919I544J2545D01*
G03X204563I313J249D01*
G02X207061Y127739I2037J-1619D01*
G37*
G36*
G01X87036Y122303D02*
G03X87650Y122295I310J252D01*
G02X87614Y119347I1750J-1496D01*
G03X87000Y119355I-310J-252D01*
G02X83503Y119350I-1751J1495D01*
G03X82897I-303J-260D01*
G02Y122350I-1747J1500D01*
G03X83503I303J260D01*
G02X87036Y122303I1747J-1500D01*
G37*
G36*
G01X729200Y443083D02*
G03X729883Y442800I400J0D01*
G01X760874Y473791D01*
Y489918D01*
X760859Y489953D01*
G02X763852Y488662I2140J847D01*
G01X763726Y488611D01*
Y472609D01*
X729200Y438083D01*
Y274501D01*
X729232Y274451D01*
G02Y271949I-1932J-1251D01*
G01X729200Y271899D01*
Y123300D01*
X724400Y118500D01*
X723510D01*
X723477Y118488D01*
G02X721897I-790J2162D01*
G01X721864Y118500D01*
X721700D01*
Y118567D01*
X721595Y118624D01*
G02X721581Y122669I1092J2026D01*
G01X721606Y122683D01*
X721700Y122776D01*
Y444400D01*
X724898Y447598D01*
Y454902D01*
X724500Y455300D01*
X724000D01*
X723296Y454596D01*
X723285Y454579D01*
G02X722655Y453949I-1840J1210D01*
G01X722638Y453938D01*
X720194Y451494D01*
X720195Y451410D01*
G02X717972Y449187I-2202J-21D01*
G01X717888Y449188D01*
X717000Y448300D01*
X716374D01*
G03X715985Y447806I0J-400D01*
G02X711705I-2140J-517D01*
G03X711316Y448300I-389J94D01*
G01X709517D01*
X709462Y448254D01*
G02X706656I-1403J1697D01*
G01X706601Y448300D01*
X706300D01*
X705700Y448900D01*
Y455000D01*
X705858Y455158D01*
Y466739D01*
X705836Y466782D01*
G02X709909Y468927I2054J1038D01*
G01X709923Y468902D01*
X710260Y468564D01*
Y460526D01*
G03X710943Y460243I400J0D01*
G01X720600Y469900D01*
Y489200D01*
X701619Y508181D01*
X701492Y508121D01*
G02X698429Y511184I-980J2083D01*
G01X698489Y511311D01*
X698100Y511700D01*
Y520300D01*
X681100Y537300D01*
Y544400D01*
X677756Y547744D01*
X654044D01*
G03X653800Y547027I0J-400D01*
G02X650156Y544689I-1400J-1827D01*
G03X649483Y544883I-390J-89D01*
G01X647900Y543300D01*
X635100D01*
X628650Y549750D01*
Y557750D01*
X629900Y559000D01*
X644504D01*
X644508D01*
G02X644692I92J-2300D01*
G01X644696D01*
X645300D01*
X645467Y558833D01*
X645503Y558818D01*
G02X646718Y557603I-903J-2118D01*
G01X646733Y557567D01*
X650500Y553800D01*
X685400D01*
X686652Y552548D01*
X686670D01*
X691716Y547501D01*
G03X692399Y547771I283J283D01*
G02X694771Y545399I2301J-71D01*
G03X694501Y544716I13J-400D01*
G01X709791Y529426D01*
X717693D01*
X717744Y529549D01*
G02X722154Y528911I2122J-893D01*
G03X722697Y528583I397J44D01*
G02X724562Y528502I841J-2143D01*
G03X724823Y528579I89J179D01*
G02X725776Y525338I1977J-1179D01*
G03X725515Y525261I-89J-179D01*
G02X722501Y524385I-1977J1179D01*
G03X721948Y524172I-180J-357D01*
G02X717560Y524470I-2148J828D01*
G01X717523Y524624D01*
X707801D01*
X704383Y528042D01*
G03X703700Y527759I-283J-283D01*
G01Y516400D01*
X726300Y493800D01*
Y486200D01*
X727600Y484900D01*
X742000D01*
X742600Y484300D01*
Y481100D01*
X743200Y480500D01*
X744400D01*
X744842Y480058D01*
X744853Y480050D01*
G02X745445Y479366I-1334J-1752D01*
G01X745459Y479341D01*
X746200Y478600D01*
X747700D01*
X748105Y478195D01*
X748119Y478185D01*
G02X748641Y477663I-1274J-1796D01*
G01X748651Y477649D01*
X749100Y477200D01*
Y472300D01*
X747700Y470900D01*
X745900D01*
X743000Y473800D01*
X742000D01*
X740948Y472748D01*
X740944Y472671D01*
G02X738863Y470590I-2199J118D01*
G01X738786Y470586D01*
X737319Y469119D01*
X737304Y469081D01*
G02X736076Y467853I-2045J817D01*
G01X736038Y467838D01*
X733676Y465476D01*
X733737Y465349D01*
G02X730800Y462412I-1986J-951D01*
G01X730673Y462473D01*
X728765Y460565D01*
X728753Y460504D01*
G02X728433Y459705I-2165J403D01*
G01X728400Y459655D01*
Y458358D01*
X729302Y457457D01*
Y444988D01*
X729200Y444887D01*
Y443083D01*
G37*
G36*
G01X39800Y169698D02*
X31126D01*
X24802Y163374D01*
Y109524D01*
X24898Y109465D01*
G02X19415Y105300I-1918J-3166D01*
G01X19401Y105350D01*
X18398Y106353D01*
Y166026D01*
X28474Y176102D01*
X39800D01*
G02Y169698I0J-3202D01*
G37*
G36*
G01X242758Y83394D02*
G03X242754Y82832I283J-283D01*
G02X239475Y82859I-1653J-1602D01*
G03X239479Y83421I-283J283D01*
G02X240149Y87104I1653J1602D01*
G03X240349Y87614I-171J361D01*
G02X243471Y86385I2138J852D01*
G03X243271Y85875I171J-361D01*
G02X242758Y83394I-2139J-851D01*
G37*
G36*
G01X383226Y119977D02*
Y74421D01*
X383235Y74394D01*
G02X378815I-2210J-646D01*
G01X378824Y74421D01*
Y119977D01*
X378815Y120004D01*
G02X383235I2210J646D01*
G01X383226Y119977D01*
G37*
G36*
G01X284916Y45542D02*
G03X284296I-310J-253D01*
G02Y48836I-2014J1647D01*
G03X284916I310J253D01*
G02X288775Y49024I2014J-1647D01*
G03X289367Y49051I284J282D01*
G02X289528Y45559I2006J-1657D01*
G03X288936Y45532I-284J-282D01*
G02X284916Y45542I-2006J1657D01*
G37*
G36*
G01X300673Y44190D02*
G03Y43510I211J-340D01*
G02X297927I-1373J-2210D01*
G03Y44190I-211J340D01*
G02X300673I1373J2210D01*
G37*
G36*
G01X264032Y81903D02*
X264040Y81876D01*
G02X259620I-2210J-646D01*
G01X259628Y81903D01*
Y87081D01*
X257435Y89274D01*
G03X256760Y88917I-282J-283D01*
G02X254928Y90749I-2262J-430D01*
G03X255285Y91424I74J393D01*
G01X252655Y94054D01*
X252552D01*
X250606Y96000D01*
X250581Y96014D01*
G02X253706Y99139I1106J2019D01*
G01X253720Y99114D01*
X254376Y98458D01*
X254479D01*
X264032Y88905D01*
Y81903D01*
G37*
G36*
G01X178432Y96543D02*
G02X175995Y96451I-1132J-2343D01*
G03X175968Y97157I-201J346D01*
G02X175922Y101820I1132J2343D01*
G03X175935Y102526I-181J356D01*
G02X178378Y102480I1265J2274D01*
G03X178365Y101774I181J-356D01*
G02X178405Y97249I-1265J-2274D01*
G03X178432Y96543I201J-346D01*
G37*
G36*
G01X83298Y191046D02*
G02X81649Y189619I502J-2246D01*
G03X81187Y190152I-374J142D01*
G02X82836Y191579I-502J2246D01*
G03X83298Y191046I374J-142D01*
G37*
G36*
G01X123722Y226378D02*
G02X123674Y224108I1978J-1177D01*
G03X122978Y224122I-352J-190D01*
G02X123026Y226392I-1978J1177D01*
G03X123722Y226378I352J190D01*
G37*
G36*
G01X35890Y511365D02*
G02X31416Y514015I-2290J1236D01*
G03X31221Y514607I-335J218D01*
G02X30029Y515620I806J2156D01*
G03X29340Y515629I-347J-199D01*
G02X29741Y518575I-3159J1930D01*
G03X30407Y518400I385J110D01*
G02X31261Y518935I1619J-1636D01*
G03X31500Y519459I-133J377D01*
G02X34461Y522959I2421J955D01*
G03X34915Y523500I83J391D01*
G02X34851Y523679I2417J965D01*
G03X34391Y523949I-381J-122D01*
G02X35285Y528690I-511J2551D01*
G03X35901Y529008I216J337D01*
G02X39315Y526886I2299J-108D01*
G03X39218Y526261I194J-350D01*
G02X36789Y521927I-1889J-1789D01*
G03X36335Y521386I-83J-391D01*
G02X34533Y517885I-2414J-972D01*
G03X34242Y517388I94J-389D01*
G02X34056Y515679I-2216J-623D01*
G03X34301Y515106I353J-188D01*
G02X35039Y514768I-701J-2506D01*
G03X35314Y514820I111J166D01*
G02X36157Y511448I1886J-1320D01*
G03X35890Y511365I-91J-178D01*
G37*
G36*
G01X760583Y514431D02*
G02X760195Y511883I1692J-1561D01*
G03X759540Y511982I-361J-172D01*
G02X755563Y513826I-1692J1561D01*
G03X755405Y514047I-198J25D01*
G02X754628Y518246I457J2256D01*
G03X754726Y518834I-214J338D01*
G02X754224Y520157I1797J1439D01*
G03X753549Y520427I-400J-20D01*
G02X750227Y520587I-1584J1670D01*
G03X749624I-301J-262D01*
G02X746262Y520466I-1738J1510D01*
G03X745697I-282J-284D01*
G02Y523728I-1624J1631D01*
G03X746262I283J284D01*
G02X749624Y523607I1624J-1631D01*
G03X750227I302J262D01*
G02X754264Y522212I1738J-1510D01*
G03X754939Y521942I400J20D01*
G02X757757Y518329I1585J-1669D01*
G03X757659Y517741I214J-338D01*
G02X758147Y516020I-1797J-1439D01*
G03X758305Y515799I198J-25D01*
G02X759928Y514530I-457J-2256D01*
G03X760583Y514431I361J172D01*
G37*
G36*
G01X365003Y78461D02*
G02X360583I-2210J-646D01*
G01X360592Y78488D01*
Y125423D01*
X360583Y125450D01*
G02X363122Y128374I2210J646D01*
G01X363221Y128360D01*
X372323Y137462D01*
G03X372255Y138082I-283J283D01*
G02X371869Y138393I1243J1938D01*
G03X371303I-283J-283D01*
G01X366193Y133282D01*
X365804D01*
X365777Y133274D01*
G02X364285Y137625I-646J2210D01*
G01X364324Y137640D01*
X401018Y174334D01*
Y455382D01*
X414555Y468920D01*
X414569Y468945D01*
G02X418479Y469152I2019J-1106D01*
G03X419069Y469077I329J228D01*
G02X422870Y467157I1506J-1741D01*
G01X422863Y467065D01*
X425747Y464181D01*
G03X426373Y464257I283J283D01*
G02X428989Y465277I1971J-1190D01*
G01X429016Y465268D01*
X433644D01*
X436219Y462694D01*
X436244Y462680D01*
G02X437348Y460015I-1106J-2019D01*
G01X437340Y459988D01*
Y196252D01*
X364994Y123907D01*
Y78488D01*
X365003Y78461D01*
G37*
G54D35*
X55295Y479672D03*
G54D32*
X59900Y40600D03*
X55800Y61300D03*
X70700Y45800D03*
X50800Y39500D03*
X65700Y49800D03*
X45900Y50000D03*
X75500Y60800D03*
X65500D03*
X60800Y72500D03*
X70500Y72000D03*
X57200Y175300D03*
X80400Y47800D03*
X90900Y42400D03*
X87900Y47800D03*
X85300Y70200D03*
X121700Y75300D03*
X100000Y75600D03*
X111100Y75500D03*
X142101Y98650D03*
X142167Y106366D03*
X147500Y90200D03*
X126300Y180209D03*
X209100Y51700D03*
X191700Y63300D03*
X209200Y65100D03*
X200700Y51700D03*
X185100Y55900D03*
X208900Y58600D03*
X192000Y55900D03*
X200700Y58300D03*
X184700Y63100D03*
X151800Y72400D03*
X163500Y105500D03*
X163300Y95900D03*
X165200Y79500D03*
X158000Y79600D03*
X154500Y90000D03*
X209000Y72300D03*
X201500D03*
X177300Y88500D03*
X184700D03*
X190700Y77800D03*
X201200Y65600D03*
X191000Y71300D03*
X184500Y71200D03*
X177400Y71400D03*
X177500Y77900D03*
X183700Y78100D03*
X191500Y88500D03*
X351800Y36300D03*
X360500Y36700D03*
X321300Y37100D03*
X329900D03*
X330000Y42800D03*
X360500Y42600D03*
X351800Y42200D03*
X321300Y43200D03*
X644900Y538300D03*
X726000Y650700D03*
X720000Y650800D03*
X733000Y650600D03*
X740000D03*
X745413Y854763D03*
G54D30*
X10551Y623622D03*
Y741732D03*
X18425Y553544D03*
X32204D03*
X18425Y623622D03*
X32204D03*
X18425Y671654D03*
X32204D03*
X18425Y741732D03*
X32204D03*
G54D34*
X42700Y110500D03*
X79500Y85700D03*
X31500Y185700D03*
X69800Y176800D03*
X76250Y148850D03*
X70200Y199300D03*
X29600Y200100D03*
X74700Y191700D03*
X70675Y145000D03*
X51600Y217000D03*
X64700Y215100D03*
X60069Y237965D03*
X33400Y266400D03*
X50500Y243100D03*
X76019Y222534D03*
X38800Y535700D03*
X63862Y512438D03*
X57500Y662600D03*
X59379Y644787D03*
X64000Y765600D03*
X60122Y747800D03*
X47100Y746000D03*
X111700Y106100D03*
X117500Y106200D03*
X132500Y124600D03*
X113815Y194333D03*
X122400Y199000D03*
X84641Y204036D03*
X93303Y154970D03*
X85713Y151540D03*
X84900Y145300D03*
X109400Y225400D03*
X85300Y755100D03*
X84100Y769000D03*
X220131Y58163D03*
X197900Y82000D03*
X210356Y99104D03*
X210680Y84396D03*
X201614Y89932D03*
X212028Y93512D03*
X200100Y101200D03*
X170302Y147100D03*
X158100Y166800D03*
X160311Y141680D03*
X154300Y227900D03*
X256928Y69301D03*
X251700Y135484D03*
X249600Y428100D03*
X223596Y782163D03*
X282413Y798410D03*
X271970Y798668D03*
X305437Y798205D03*
X294148Y798547D03*
X315696Y798445D03*
X388884Y468631D03*
X387143Y462647D03*
X361814Y796557D03*
X501800Y387600D03*
X457091Y486699D03*
X447090Y497242D03*
X447307Y511890D03*
X469932Y518034D03*
X483008Y500529D03*
X482183Y535169D03*
X487073Y554094D03*
X483530Y541762D03*
X471410Y490049D03*
X506100Y380000D03*
X523200Y399400D03*
X517041Y388700D03*
X536928Y411324D03*
X514000Y486293D03*
X508306Y428179D03*
X514073Y552477D03*
X503300Y539700D03*
X637200Y393900D03*
X629100Y536000D03*
X662100Y394600D03*
X702000Y485700D03*
X707700Y476500D03*
X674375Y509826D03*
X663600Y535395D03*
X705927Y538650D03*
X671915Y543133D03*
X682015Y493633D03*
X656817Y567131D03*
X669200Y559600D03*
X686308Y834802D03*
X690211Y827401D03*
X758200Y338900D03*
X756700Y370600D03*
X762900Y387400D03*
X716300Y517125D03*
X722682Y538700D03*
X724000Y532600D03*
X729600Y540400D03*
X729700Y551500D03*
X737297Y517903D03*
X725100Y519600D03*
X742000Y505000D03*
X717879Y564572D03*
X737400Y576200D03*
X766358Y564600D03*
X727700Y584400D03*
X758400Y568500D03*
X742600Y577100D03*
X729250Y850000D03*
X733796Y854172D03*
G54D33*
X30854Y106299D03*
X41142Y135669D03*
Y155669D03*
Y145669D03*
X26181Y537559D03*
Y527559D03*
X41142Y655669D03*
Y635669D03*
Y763780D03*
Y753780D03*
Y773780D03*
G54D38*
X286982Y828335D03*
X276982D03*
X286982Y818335D03*
X276982D03*
X356982Y828335D03*
X346982D03*
X336982D03*
X326982D03*
X316982D03*
X306982D03*
X296982D03*
X356982Y818335D03*
X346982D03*
X336982D03*
X326982D03*
X316982D03*
X306982D03*
X296982D03*
X366982Y828335D03*
Y818335D03*
G54D29*
X144843Y812994D03*
Y860234D03*
G54D37*
X182681Y580832D03*
G54D28*
X54724Y557087D03*
Y620079D03*
Y675197D03*
Y738189D03*
X144843Y798779D03*
Y874449D03*
G54D27*
X-33503Y269685D03*
G54D31*
X29528Y19685D03*
X76772D03*
X108268Y905512D03*
X155512D03*
G54D36*
X109410Y796831D03*
Y876397D03*
X168465Y796831D03*
Y876397D03*
G54D26*
X-59094Y277559D03*
X-7913D03*
%LPD*%
G75*
G36*
G01X405421Y174929D02*
X405420Y453558D01*
X417669Y465806D01*
X417694Y465820D01*
G03X418094Y466098I-1106J2019D01*
G02X418684Y466023I261J-303D01*
G03X420754Y465041I1891J1313D01*
G01X420846Y465048D01*
X424270Y461623D01*
Y192813D01*
X406103Y174646D01*
G02X405421Y174929I-282J283D01*
G37*
G36*
G01X427123Y193229D02*
X427124Y460492D01*
G02X427645Y460873I400J0D01*
G03X428989Y460857I698J2194D01*
G01X429016Y460866D01*
X431820D01*
X432936Y459749D01*
Y198076D01*
X427806Y192946D01*
G02X427123Y193229I-283J283D01*
G37*
G36*
G01X674600Y464300D02*
X658200Y480700D01*
Y482400D01*
X658891Y483092D01*
X676009D01*
X679500Y479600D01*
Y464800D01*
X679000Y464300D01*
X674600D01*
G37*
G54D10*
X-1011811Y-15748D03*
Y940945D03*
X-59094Y277559D03*
X-7913D03*
X-33503Y269685D03*
X54724Y557087D03*
Y620079D03*
Y675197D03*
Y738189D03*
X144843Y798779D03*
Y812994D03*
Y874449D03*
Y860234D03*
X716535Y39370D03*
X775591Y-15748D03*
Y940944D03*
G54D20*
G01X746669Y740179D02*
X756621D01*
X762650Y734150D01*
G01X761840Y822400D02*
X747116D01*
X733066Y836450D01*
G54D11*
X-138100Y222300D03*
Y241300D03*
Y260300D03*
Y279300D03*
Y298300D03*
Y317300D03*
Y336300D03*
X-70100Y222300D03*
X-87100D03*
X-104100D03*
X-121100D03*
X-70100Y241300D03*
X-87100D03*
X-104100D03*
X-121100D03*
X-70100Y260300D03*
X-87100D03*
X-104100D03*
X-121100D03*
X-70100Y279300D03*
X-87100D03*
X-104100D03*
X-121100D03*
X-70100Y298300D03*
X-87100D03*
X-104100D03*
X-121100D03*
X-70100Y317300D03*
X-87100D03*
X-104100D03*
X-121100D03*
X-70100Y336300D03*
X-87100D03*
X-104100D03*
X-121100D03*
X-2100Y222300D03*
X-19100D03*
X-36100D03*
X-53100D03*
X-2100Y241300D03*
X-19100D03*
X-36100D03*
X-53100D03*
X-2100Y260300D03*
X-19100D03*
X-36300Y260000D03*
X-53100Y260300D03*
X9243Y334400D03*
X-1900Y288300D03*
X-49400Y284500D03*
X-19600Y279500D03*
X-36100Y279300D03*
X-2100Y298300D03*
X-19100D03*
X-36100D03*
X-53100D03*
X-2100Y317300D03*
X-19100D03*
X-36100D03*
X-53100D03*
X-2100Y336300D03*
X-19100D03*
X-36100D03*
X-53100D03*
X-1600Y413600D03*
Y394600D03*
Y375600D03*
Y356600D03*
X-52600Y413600D03*
X-35600D03*
X-18600D03*
X-52600Y394600D03*
X-35600D03*
X-18600D03*
X-52600Y375600D03*
X-35600D03*
X-18600D03*
X-52600Y356600D03*
X-35600D03*
X-18600D03*
X-19400Y483400D03*
X-2400D03*
X-36400D03*
X-53400D03*
X-1500Y470300D03*
Y451300D03*
Y432300D03*
X-52500Y470300D03*
X-35500D03*
X-18500D03*
X-52500Y451300D03*
X-35500D03*
X-18500D03*
X-52500Y432300D03*
X-35500D03*
X-18500D03*
X8788Y453864D03*
X-19400Y502400D03*
X-2400D03*
X-36400D03*
X-53400D03*
X63400Y89300D03*
X51900Y83600D03*
X43980Y86200D03*
X68000Y87750D03*
X42700Y110500D03*
X67300Y107200D03*
X63100Y107300D03*
X48100Y133900D03*
X59200Y95573D03*
X51800Y93500D03*
X79600Y91500D03*
X51900Y89900D03*
X79500Y85700D03*
X77200Y95500D03*
X69800Y176800D03*
X31500Y185700D03*
X76250Y148850D03*
X70200Y199300D03*
X47900Y145500D03*
X48100Y153800D03*
X43800Y204800D03*
X38800Y194300D03*
X38700Y199700D03*
X73700D03*
X49500Y169300D03*
X61751Y181464D03*
X44100Y200600D03*
X49286Y203671D03*
X69000Y202700D03*
X77200Y189000D03*
X60200Y193550D03*
X29600Y200100D03*
X26100Y187300D03*
X39800Y172900D03*
X27800Y191100D03*
X74700Y191700D03*
X70675Y145000D03*
X60009Y255077D03*
X55624Y255132D03*
X59523Y271123D03*
X60102Y263180D03*
X55883Y263570D03*
X33400Y266400D03*
X59258Y246890D03*
X60069Y237965D03*
X64700Y215100D03*
X51600Y217000D03*
X50500Y243100D03*
X70636Y272953D03*
X79189Y235119D03*
X43900Y209000D03*
X72001Y265901D03*
X69400Y207400D03*
X76019Y222534D03*
X42507Y296616D03*
X59316Y300366D03*
X59096Y289139D03*
X59523Y281330D03*
X52257Y276649D03*
X55420Y288656D03*
X17100Y311700D03*
X43181Y278603D03*
X39563Y307968D03*
X21876Y282289D03*
X41418Y287473D03*
X61776Y367194D03*
X43345Y386857D03*
X43639Y374043D03*
X29700Y355000D03*
X27284Y358500D03*
X67527Y381818D03*
X43569Y379314D03*
X65605Y367307D03*
X51422Y473540D03*
X24315Y472668D03*
X47307Y465104D03*
X29064Y471345D03*
X55295Y479672D03*
X20715Y485712D03*
X20276Y477090D03*
X20928Y453864D03*
X21300Y468000D03*
X38800Y535700D03*
X38200Y528900D03*
X51383Y514037D03*
X63862Y512438D03*
X73542Y514340D03*
X37200Y513500D03*
X32026Y516764D03*
X60800Y505200D03*
X56121Y494271D03*
X21090Y497108D03*
X54659Y513125D03*
X67140Y511501D03*
X50893Y534434D03*
X66300Y548000D03*
X67244Y535455D03*
X72677Y528615D03*
X69220Y614992D03*
X59379Y644787D03*
X57500Y662600D03*
X47000Y645300D03*
X69911Y676938D03*
X73900Y664900D03*
X77000Y646200D03*
X72930Y645818D03*
X67257Y643668D03*
X60122Y747800D03*
X64000Y765600D03*
X47100Y746000D03*
X69217Y732676D03*
X73325Y760926D03*
X67809Y758190D03*
X65447Y711413D03*
X62066Y711051D03*
X65356Y707010D03*
X61193Y706973D03*
X73282Y778907D03*
X106300Y105900D03*
X81150Y120850D03*
X89400Y120800D03*
X85250Y120850D03*
X117500Y106200D03*
X85000Y107800D03*
X111700Y106100D03*
X89000Y107700D03*
X82400Y89500D03*
X132500Y124600D03*
X83800Y188800D03*
X111482Y202800D03*
X113815Y194333D03*
X122400Y199000D03*
X80685Y192398D03*
X84641Y204036D03*
X79900Y148700D03*
X103300Y160900D03*
X112000Y160700D03*
X119900Y162200D03*
X125300Y162300D03*
X122100Y203300D03*
X96900Y189286D03*
X107771Y182699D03*
X145400Y161955D03*
X114700Y157000D03*
X107672Y156597D03*
X98700Y156200D03*
X122200Y156700D03*
X80207Y139965D03*
X81200Y176000D03*
X93303Y154970D03*
X144950Y177338D03*
X85713Y151540D03*
X84900Y145300D03*
X125700Y225200D03*
X121000Y225300D03*
X109400Y225400D03*
X90813D03*
X79800Y225900D03*
X87227Y242891D03*
X87263Y264658D03*
X90652Y265960D03*
X87698Y246708D03*
X94051Y265872D03*
X91230Y247047D03*
X91819Y250396D03*
X94793Y252595D03*
X98211Y252758D03*
X142933Y251431D03*
X132651Y255357D03*
X138228Y260175D03*
X124933Y270414D03*
X136427Y251413D03*
X124874Y273953D03*
X137809Y247647D03*
X135592Y257933D03*
X116566Y254205D03*
X114229Y270684D03*
X119242Y252107D03*
X112042Y275903D03*
X121685Y249741D03*
X121741Y246341D03*
X118219Y274497D03*
X122572Y258147D03*
X121599Y274869D03*
X130567Y258051D03*
X113558Y261260D03*
X111008Y242830D03*
X106381Y259865D03*
X106504Y243329D03*
X103610Y268626D03*
X102713Y242975D03*
X103003Y260260D03*
X108652Y247260D03*
X107887Y266647D03*
X101242Y265901D03*
X100415Y246679D03*
X126611Y258265D03*
X84863Y229783D03*
X134529Y264470D03*
X137190Y266587D03*
X131901Y267444D03*
X132163Y271041D03*
X137690Y273752D03*
X110610Y206436D03*
X125600Y221200D03*
X113863Y228669D03*
X102559Y228575D03*
X97885Y228339D03*
X147013Y225483D03*
X122000Y207300D03*
X94600Y206900D03*
X94548Y211258D03*
X109534Y314564D03*
X92682Y331571D03*
X140103Y328216D03*
X117460Y335158D03*
X128964Y339470D03*
X148102Y338366D03*
X119603Y285731D03*
X124478Y280855D03*
X95202Y290958D03*
X98565Y290455D03*
X102107Y290439D03*
X105603Y291092D03*
X95146Y279609D03*
X110808Y291075D03*
X98546Y279609D03*
X114915Y290203D03*
X104413Y278608D03*
X117027Y278475D03*
X148834Y284832D03*
X107750Y277953D03*
X128918Y307533D03*
X135308Y276806D03*
X139784Y276432D03*
X142241Y278783D03*
X121477Y314973D03*
X135613Y308903D03*
X95400Y383083D03*
X84200Y380000D03*
X118744Y525279D03*
X140399Y525238D03*
X129199Y525271D03*
X107103Y525057D03*
X95599Y525026D03*
X84799Y524898D03*
X90878Y585185D03*
X85654Y659044D03*
X83960Y632636D03*
X90681Y690157D03*
X90174Y678675D03*
X85600Y647837D03*
X83500Y653600D03*
Y640044D03*
X84900Y747900D03*
X93840Y699686D03*
X90814Y734451D03*
X91027Y724985D03*
X91094Y715818D03*
X84703Y758885D03*
X84182Y764879D03*
X90746Y712435D03*
X90947Y709040D03*
X91003Y705214D03*
X91130Y701741D03*
X85300Y755100D03*
X85000Y775900D03*
X84100Y769000D03*
X220131Y58163D03*
X197900Y82000D03*
X201237Y106350D03*
X210356Y99104D03*
X210680Y84396D03*
X201614Y89932D03*
X212028Y93512D03*
X212800Y125800D03*
X182400Y128300D03*
X175598Y128436D03*
X220100Y123600D03*
X166700Y128800D03*
X172200Y128300D03*
X179000D03*
X205628Y89404D03*
X152350Y131084D03*
X204849Y106438D03*
X200100Y101200D03*
X170302Y147100D03*
X158100Y166800D03*
X160311Y141680D03*
X219548Y174651D03*
X189600Y166700D03*
X189700Y170200D03*
X190018Y173586D03*
X188961Y162715D03*
X211700Y181600D03*
X208200Y153500D03*
X203900D03*
X200100Y146500D03*
Y150400D03*
X199100Y153800D03*
X194800D03*
X174339Y151172D03*
X178400Y152300D03*
X167015Y167633D03*
X163550Y179657D03*
X172645Y179104D03*
X177087Y178920D03*
X183120Y266103D03*
X183082Y271969D03*
X182853Y256107D03*
X183956Y261452D03*
X168010Y267909D03*
X219717Y211198D03*
X182177Y251208D03*
X154300Y227900D03*
X171200Y233000D03*
X185563Y245456D03*
X175064Y232857D03*
X185740Y240983D03*
X185502Y237383D03*
X152663Y272053D03*
X192284Y258847D03*
X150666Y243134D03*
X195698Y259749D03*
X196365Y256414D03*
X168324Y246397D03*
X171762Y258345D03*
X167894Y243024D03*
X167760Y239626D03*
X156800Y230500D03*
X152663Y267791D03*
X216335Y218212D03*
X196344Y237383D03*
X196078Y248183D03*
X196021Y244556D03*
X196151Y240983D03*
X151519Y250193D03*
X180641Y231683D03*
X186319Y268076D03*
X183043Y276658D03*
X183707Y289861D03*
X183653Y283162D03*
X184188Y340638D03*
X162135Y332650D03*
X185042Y286734D03*
X167051Y293752D03*
X188273Y285674D03*
X187118Y281963D03*
X163142Y294193D03*
X183466Y294017D03*
X152580Y285530D03*
X172818Y288683D03*
X216178Y411331D03*
X219144Y414536D03*
X195307Y355649D03*
X206775Y348954D03*
X173508Y348462D03*
X177715Y397471D03*
X212500Y395500D03*
X217800Y395900D03*
X200161Y416474D03*
X206142Y413945D03*
X206871Y397177D03*
X210042Y412265D03*
X175767Y380311D03*
X189073Y380379D03*
X185276Y380362D03*
X181242Y380481D03*
X197565Y380257D03*
X203379Y380312D03*
X169600Y380500D03*
X173864Y397677D03*
X213400Y434601D03*
X181980Y458681D03*
X210772Y431456D03*
X200453Y439066D03*
X203186Y451492D03*
X180445Y422567D03*
X176991Y463723D03*
X184750Y427953D03*
X208947Y443700D03*
X196803Y444462D03*
X201400Y434400D03*
X202764Y444274D03*
X190887Y424438D03*
X174500Y424100D03*
X182060Y443776D03*
X211243Y462005D03*
X203406Y454885D03*
X195038Y477148D03*
X180313Y446694D03*
X176915Y446556D03*
X195400Y452051D03*
X208632Y457048D03*
X181034Y427967D03*
X177700Y427300D03*
X184399Y525203D03*
X195499D03*
X206699D03*
X217899Y525103D03*
X162615Y525220D03*
X173537D03*
X151684Y525258D03*
X210223Y501477D03*
X213500Y503600D03*
X216300Y499600D03*
X193016Y496643D03*
X219492Y517832D03*
X219590Y740816D03*
X181642Y837321D03*
Y827853D03*
X181772Y818429D03*
X159926Y813000D03*
X201663Y827680D03*
X201142Y837191D03*
X181081Y856307D03*
X181124Y847013D03*
X200798Y846849D03*
X266700Y46900D03*
X263000Y47000D03*
X257500Y46900D03*
X253800Y47000D03*
X244900Y47300D03*
X248600Y47200D03*
X235000Y47500D03*
X238700Y47400D03*
X225231Y58420D03*
X254498Y88487D03*
X251687Y98033D03*
X261830Y81230D03*
X241101D03*
X256928Y69301D03*
X241132Y85023D03*
X259815Y94233D03*
X248000Y114500D03*
X242488Y88466D03*
X223948Y174292D03*
X246100Y151300D03*
Y155800D03*
Y160400D03*
X231049Y188760D03*
X251700Y135484D03*
X231350Y222067D03*
X238614Y217763D03*
X222496Y222320D03*
X223129Y210901D03*
X224664Y293860D03*
X257400Y403206D03*
X239600Y405600D03*
X237800Y411200D03*
X226576Y401835D03*
X228243Y380358D03*
X231915Y380533D03*
X244928Y367685D03*
X238151Y356092D03*
X228510Y367624D03*
X240715Y380333D03*
X222269Y402278D03*
X228949Y410741D03*
X225421Y410908D03*
X269840Y386256D03*
X239693Y396029D03*
X257500Y399300D03*
X264600Y380500D03*
X270800Y408500D03*
X261300Y402355D03*
X275500Y415400D03*
X264124Y408219D03*
X258267Y408800D03*
X233400Y409700D03*
X255010Y367624D03*
X273554Y386722D03*
X223600Y456200D03*
X246502Y472752D03*
X255622Y461532D03*
X263000Y438800D03*
X260600Y435900D03*
X258299Y432800D03*
X250400Y440000D03*
X249600Y428100D03*
X237700Y458000D03*
X269300Y486200D03*
X249600Y432500D03*
X239000Y440300D03*
X244800Y454500D03*
X229600Y460700D03*
X289200Y445100D03*
X252200Y486700D03*
X290300Y462400D03*
X290011Y456234D03*
X289000Y449200D03*
X221035Y453935D03*
X279120Y440440D03*
X276761Y443421D03*
X277575Y449398D03*
X270714Y458323D03*
X263719Y455536D03*
X259779Y456823D03*
X220768Y418393D03*
X260322Y462288D03*
X256852Y465331D03*
X258221Y469246D03*
X235069Y464940D03*
X257184Y421241D03*
X271342Y440630D03*
X235600Y433300D03*
X264775Y459236D03*
X279789Y432846D03*
X285565Y438912D03*
X250400Y473300D03*
X260481Y473769D03*
X253214Y469048D03*
X228400Y486400D03*
X228001Y474064D03*
X226000Y458700D03*
X249845Y469508D03*
X229300Y442500D03*
X225700Y496800D03*
X226115Y507011D03*
X229513Y507141D03*
X232912Y507242D03*
X224515Y532633D03*
X237336Y531828D03*
X236700Y539300D03*
X240400Y534500D03*
X245800D03*
X241300Y539300D03*
X236300Y535600D03*
X243200Y531700D03*
X288586Y493703D03*
X268215Y490733D03*
X251755Y491731D03*
X270700Y495400D03*
X274315Y497133D03*
X283657Y532832D03*
X280259Y532714D03*
X232200Y492100D03*
X231739Y495469D03*
X248286Y489208D03*
X242100Y489000D03*
X268600Y529800D03*
X256300Y531400D03*
X289400Y511700D03*
X243300Y527900D03*
X247256Y529218D03*
X251700Y531500D03*
X268500Y525800D03*
X238118Y492166D03*
X246132Y492160D03*
X289405Y515437D03*
X228500Y498900D03*
X281183Y592936D03*
X223671Y740896D03*
X228249Y761450D03*
X223129Y764830D03*
X271970Y798668D03*
X282413Y798410D03*
X228021Y787335D03*
X223596Y782163D03*
X236973Y795418D03*
X237950Y774979D03*
X237815Y779065D03*
X226949Y782735D03*
X235169Y791455D03*
X240130Y789012D03*
X277254Y852624D03*
X314000Y405200D03*
X316800Y415900D03*
X299800Y398500D03*
X332600Y400100D03*
X305456Y481787D03*
X335532Y485626D03*
X323215Y485633D03*
X304783Y467192D03*
X295115Y476433D03*
Y473033D03*
X297715Y479588D03*
X306603Y459523D03*
X301437Y426833D03*
X304200Y432600D03*
X300603Y432406D03*
X309200Y444700D03*
X331800Y440400D03*
X331900Y444600D03*
X356700Y437500D03*
X348800D03*
X341500Y437400D03*
X291300Y468600D03*
X308900Y449100D03*
X327900Y438100D03*
X341430Y459351D03*
X345735Y460843D03*
X349800Y460000D03*
X353698Y460323D03*
X357812Y460406D03*
X297238Y429641D03*
X304550Y424222D03*
X300059Y422844D03*
X318015Y493833D03*
X334315Y496733D03*
X330815Y493433D03*
X327115Y489533D03*
X344815Y494933D03*
X321415Y497133D03*
X304000Y538500D03*
X308800Y540925D03*
X350400Y512000D03*
X335600Y511400D03*
X304700Y509500D03*
X317900Y520100D03*
X314628Y517729D03*
X343905Y519116D03*
X324400Y570500D03*
X346510Y796385D03*
X350765D03*
X315696Y798445D03*
X294148Y798547D03*
X305437Y798205D03*
X362793Y77815D03*
Y126096D03*
X381025Y73748D03*
Y120650D03*
X373496Y140021D03*
X365131Y135484D03*
X413900Y396400D03*
X428343Y463067D03*
X420575Y467336D03*
X382695Y467033D03*
Y471133D03*
X388884Y468631D03*
X387143Y462647D03*
X378700Y437600D03*
X371200Y437800D03*
X363800Y437700D03*
X428616Y429466D03*
X391500Y459000D03*
X399900Y458600D03*
X421273Y439381D03*
X361533Y460222D03*
X365241Y460010D03*
X416588Y467839D03*
X361814Y796557D03*
X500295Y401715D03*
X501800Y387600D03*
X473838Y385675D03*
X474106Y382285D03*
X500526Y394177D03*
X473605Y389068D03*
X499764Y411324D03*
X497279Y382551D03*
X435138Y460661D03*
X457091Y486699D03*
X475600Y462100D03*
X452300Y420900D03*
X458900Y446600D03*
X483100Y449900D03*
X488500Y474200D03*
X450300Y459900D03*
X471300Y482200D03*
X449000Y480000D03*
X438316Y449493D03*
X438294Y453811D03*
X501700Y477200D03*
X483530Y541762D03*
X487073Y554094D03*
X482183Y535169D03*
X483008Y500529D03*
X469932Y518034D03*
X447307Y511890D03*
X447090Y497242D03*
X471410Y490049D03*
X498994Y488322D03*
X501802Y490240D03*
X494400Y493600D03*
Y497500D03*
X471650Y493916D03*
X494410Y501344D03*
X458713Y518034D03*
X482200Y529100D03*
X484200Y538000D03*
X483800Y545700D03*
X452652Y495705D03*
X465900Y501200D03*
X523200Y399400D03*
X506100Y380000D03*
X517041Y388700D03*
X513500Y399060D03*
X520900Y388100D03*
X536928Y411324D03*
X514000Y486293D03*
X508306Y428179D03*
X523462Y423957D03*
X503923Y423910D03*
X536736Y418540D03*
X504500Y479500D03*
X514073Y552477D03*
X503300Y539700D03*
X529000Y550500D03*
X502318Y535328D03*
X521002Y555911D03*
X525300Y552800D03*
X516900Y561200D03*
X528000Y562900D03*
X512700Y560000D03*
X637200Y393900D03*
X629100Y536000D03*
X632600Y555200D03*
X636200Y555100D03*
X640100Y550600D03*
X638300Y511800D03*
X641800Y519000D03*
X639500Y521900D03*
X641700Y510300D03*
X662100Y394600D03*
X667979Y486293D03*
X702400Y431500D03*
X698300Y431600D03*
X702000Y485700D03*
X688615Y485133D03*
X693509Y431701D03*
X689111Y431612D03*
X684869Y431611D03*
X680738Y431633D03*
X711409Y467621D03*
X707700Y476500D03*
X707890Y467821D03*
X684259Y476130D03*
X682774Y449737D03*
X667745Y456089D03*
X662604Y463284D03*
X671915Y543133D03*
X694700Y547700D03*
X688800Y540450D03*
X702400Y554800D03*
X705927Y538650D03*
X663600Y535395D03*
X644600Y556700D03*
X652400Y545200D03*
X674375Y509826D03*
X700512Y510204D03*
X643833Y549325D03*
X702000Y546581D03*
X702400Y550600D03*
X684600Y542100D03*
X682015Y493633D03*
X665499Y556600D03*
X651800Y540295D03*
X711400Y515400D03*
X711900Y521500D03*
X675400Y538100D03*
X662200Y547300D03*
X709600Y524100D03*
X658314Y526697D03*
X672168Y538889D03*
X676115Y542633D03*
X712102Y542133D03*
X707589Y515400D03*
X700900Y539500D03*
X669200Y559600D03*
X656817Y567131D03*
X697600Y560000D03*
X701400Y560200D03*
X707391Y564566D03*
X643100Y589900D03*
X689945Y758289D03*
X700989Y759255D03*
X667982Y739870D03*
X681402Y757754D03*
X663575Y742289D03*
X668987Y731465D03*
X691075Y820814D03*
X711116Y796516D03*
X702290Y820921D03*
X680480Y773302D03*
X678755Y784815D03*
X676727Y790555D03*
X679630Y795856D03*
X680239Y802378D03*
X682693Y806283D03*
X684732Y810518D03*
X669886Y786112D03*
X666516Y784722D03*
X686308Y834802D03*
X646342Y826469D03*
X685799Y770894D03*
X690211Y827401D03*
X683715Y852233D03*
X710727Y862002D03*
X678351Y854383D03*
X679332Y841866D03*
X681156Y844982D03*
X681542Y848361D03*
X722687Y120650D03*
X727300Y273200D03*
X758200Y338900D03*
X756700Y370600D03*
X762900Y387400D03*
X768000Y457700D03*
X767700Y473300D03*
X729700Y551500D03*
X729600Y540400D03*
X724000Y532600D03*
X722682Y538700D03*
X716300Y517125D03*
X719800Y525000D03*
X719866Y528656D03*
X751965Y522097D03*
X747886D03*
X757848Y513543D03*
X752874Y534854D03*
X737297Y517903D03*
X756523Y520272D03*
X749493Y535216D03*
X725100Y519600D03*
X746000Y549700D03*
X726800Y527400D03*
X723538Y526440D03*
X742607Y549481D03*
X752100Y506500D03*
X749500Y508800D03*
X742000Y505000D03*
X762275Y512870D03*
X744073Y522097D03*
X755862Y516303D03*
X756400Y508100D03*
X756272Y534995D03*
X763000Y490800D03*
X717879Y564572D03*
X725900Y561800D03*
X737400Y576200D03*
X766358Y564600D03*
X727700Y584400D03*
X758400Y568500D03*
X742600Y577100D03*
X756100Y658700D03*
X757600Y639700D03*
X746669Y740179D03*
X743653Y744114D03*
X741453Y748054D03*
X738850Y751989D03*
X734450Y755929D03*
X730967Y759864D03*
X724305Y770450D03*
X723678Y774016D03*
X727477Y775212D03*
X724733Y779559D03*
X730028Y782297D03*
X724859Y784497D03*
X742663Y788885D03*
X729988Y787114D03*
X739510Y795264D03*
X725239Y788970D03*
X745230Y793211D03*
X729486Y791416D03*
X742370Y799077D03*
X725407Y794540D03*
X747659Y796960D03*
X744790Y802781D03*
X749593Y803991D03*
X747556Y808994D03*
X749629Y812608D03*
X722443Y826463D03*
X721704Y829981D03*
X724858Y831254D03*
X723801Y834857D03*
X726332Y837128D03*
X733066Y836450D03*
X729250Y850000D03*
X721243Y850725D03*
X718263Y863827D03*
X745100Y859405D03*
X721112Y854419D03*
X724093Y840187D03*
X726776Y842277D03*
X733796Y854172D03*
G54D21*
G01X66931Y484968D02*
X66029Y484066D01*
X65869D01*
X63991Y482188D01*
Y475523D01*
X66431Y473083D01*
X66963D01*
G54D12*
X4800Y48600D03*
X5800Y6400D03*
X5000Y71900D03*
Y91900D03*
X5100Y111800D03*
X4900Y130400D03*
X5000Y150500D03*
X5300Y170000D03*
X9151Y473051D03*
X8672Y487593D03*
X7075Y527972D03*
X7927Y509647D03*
X8140Y637282D03*
X8246Y771416D03*
X45700Y61000D03*
X65500Y60800D03*
X75500D03*
X45900Y50000D03*
X65700Y49800D03*
X50800Y39500D03*
X70700Y45800D03*
X55800Y61300D03*
X59900Y40600D03*
X53200Y26300D03*
X50600Y6000D03*
X50500Y67700D03*
X70500Y72000D03*
X60800Y72500D03*
X57200Y175300D03*
X16158Y477255D03*
X39600Y494800D03*
X38200Y490900D03*
X35100Y494400D03*
X33600Y512600D03*
X37329Y524472D03*
X33880Y526500D03*
X33921Y520414D03*
X18809Y491871D03*
X17212Y532250D03*
X18064Y513925D03*
X18277Y641560D03*
X9844Y658803D03*
X19981Y663081D03*
X9631Y753837D03*
X19768Y758115D03*
X18383Y775694D03*
X55459Y780063D03*
X48300Y775300D03*
X87900Y47800D03*
X90900Y42400D03*
X80400Y47800D03*
X124100Y6700D03*
X110800Y48800D03*
X120200Y48400D03*
X98700Y48900D03*
X143900Y38000D03*
X108100Y35300D03*
X146900Y48500D03*
X109700Y6400D03*
X119700Y35400D03*
X139800Y31100D03*
X96300Y6100D03*
X147200Y7300D03*
X108600Y19900D03*
X126500Y20100D03*
X147500Y90200D03*
X142167Y106366D03*
X142101Y98650D03*
X111100Y75500D03*
X100000Y75600D03*
X121700Y75300D03*
X85300Y70200D03*
X126300Y180209D03*
X126700Y173500D03*
X136291Y179968D03*
X136100Y173800D03*
X134200Y217300D03*
X130000Y217200D03*
X134600Y222200D03*
X106051Y767209D03*
X122899Y825236D03*
X112762Y820958D03*
X116188Y771487D03*
X131900Y893200D03*
X120874Y857517D03*
X110737Y853239D03*
X131700Y915700D03*
X89871Y917500D03*
X209100Y51700D03*
X191700Y63300D03*
X209200Y65100D03*
X200700Y51700D03*
X185100Y55900D03*
X208900Y58600D03*
X192000Y55900D03*
X200700Y58300D03*
X184700Y63100D03*
X173200Y10900D03*
X213700Y35200D03*
X186000D03*
X197796Y12653D03*
X160600Y49100D03*
X153200Y48700D03*
X167500Y49000D03*
X160500Y19700D03*
X170400Y31100D03*
X150600Y37800D03*
X154500Y90000D03*
X158000Y79600D03*
X165200Y79500D03*
X163300Y95900D03*
X163500Y105500D03*
X151800Y72400D03*
X209000Y72300D03*
X201500D03*
X177100Y99500D03*
X177200Y104800D03*
X177300Y94200D03*
Y88500D03*
X184700D03*
X190700Y77800D03*
X201200Y65600D03*
X191000Y71300D03*
X184500Y71200D03*
X177400Y71400D03*
X177500Y77900D03*
X183700Y78100D03*
X191500Y88500D03*
X204200Y126700D03*
X206600Y130300D03*
X201900D03*
X207495Y192761D03*
X169800Y155796D03*
X165162Y155909D03*
X169709Y160049D03*
X165388Y160094D03*
X196400Y585300D03*
X179000Y624800D03*
X193600Y702400D03*
X179100Y714600D03*
X202300Y742000D03*
X189273Y902478D03*
X213138Y905780D03*
X218729Y857629D03*
X200460Y913771D03*
X282282Y47189D03*
X286930D03*
X233900Y32500D03*
X252187Y23895D03*
X286651Y14571D03*
X224431Y15210D03*
X248900Y8400D03*
X282444Y106834D03*
X225919Y88394D03*
X225937Y80731D03*
X221710Y80767D03*
X221722Y88431D03*
X230158Y88359D03*
X230123Y80805D03*
X225851Y73774D03*
X221740Y73844D03*
X229870Y73970D03*
X228169Y68374D03*
X224169Y68520D03*
X228728Y96613D03*
X224285Y96750D03*
X258741Y193852D03*
X256823Y221979D03*
X246169Y246270D03*
X230774Y270268D03*
X241694Y274956D03*
X228635Y385956D03*
X232788Y385893D03*
X229764Y513034D03*
X234416Y512963D03*
X238924Y512390D03*
X243100Y516300D03*
X245963Y511890D03*
X250975Y511729D03*
X255500Y514000D03*
X264000Y513400D03*
X277300Y572500D03*
X259600Y568400D03*
X271949Y648699D03*
X272588Y681087D03*
X244248Y682153D03*
X255542Y665532D03*
X241904Y652321D03*
X289634Y659352D03*
X284520Y743307D03*
X282176Y713475D03*
X230823Y823850D03*
X253623Y867319D03*
X254262Y899707D03*
X225922Y900773D03*
X237216Y884152D03*
X223578Y870941D03*
X285585Y897363D03*
X283241Y867531D03*
X264212Y903112D03*
X299300Y41300D03*
X321300Y43200D03*
X351800Y42200D03*
X360500Y42600D03*
X330000Y42800D03*
X329900Y37100D03*
X321300D03*
X360500Y36700D03*
X291373Y47394D03*
X299300Y46400D03*
X351800Y36300D03*
X299600Y62100D03*
X351900Y62000D03*
X360200Y62300D03*
X329500Y62600D03*
X321300Y63100D03*
X325006Y15636D03*
X299500Y68200D03*
X352000Y68000D03*
X360200Y68200D03*
X329600D03*
X321400Y68500D03*
X344663Y108965D03*
X312275Y98098D03*
X354197Y158187D03*
X301140Y161383D03*
X352066Y262596D03*
X307320Y223390D03*
X301781Y258122D03*
X322022Y279856D03*
X320207Y428442D03*
X320166Y432442D03*
X309648Y582024D03*
X319679Y655730D03*
X320318Y688118D03*
X291978Y689184D03*
X303272Y672563D03*
X347378Y688332D03*
X358672Y671711D03*
X345034Y658500D03*
X302115Y693462D03*
X360803Y704312D03*
X333102Y737766D03*
X344396Y721145D03*
X330758Y707934D03*
X312221Y709853D03*
X312860Y742241D03*
X295814Y726686D03*
X319171Y767846D03*
X313959Y724732D03*
X354623Y896937D03*
X352279Y867105D03*
X313286Y863909D03*
X313925Y896297D03*
X296879Y880742D03*
X332436Y858576D03*
X337648Y901690D03*
X382100Y61900D03*
X401343Y58465D03*
X394098Y20059D03*
X362775D03*
X412506Y33484D03*
X382200Y68500D03*
X410025Y87658D03*
X390208Y180135D03*
X366982Y198886D03*
X407769Y204757D03*
X384668Y247681D03*
X376144Y279856D03*
X380956Y408290D03*
X376513Y408085D03*
X371865D03*
X380392Y416962D03*
X375949Y416757D03*
X371301D03*
X366653Y416484D03*
X367217Y407812D03*
X366719Y424200D03*
X371367Y424473D03*
X376015D03*
X380458Y424678D03*
X414894Y453432D03*
X419296Y449111D03*
X423572Y453454D03*
X419092Y457572D03*
X419225Y453324D03*
X410200Y474200D03*
X410179Y469769D03*
X375079Y654878D03*
X375718Y687266D03*
X430267Y679595D03*
X413860Y696428D03*
X400222Y683217D03*
X388817Y692040D03*
X420252Y725194D03*
X420891Y757582D03*
X392551Y758648D03*
X403845Y742027D03*
X390207Y728816D03*
X361442Y736700D03*
X430906Y711983D03*
X402566Y713049D03*
X395450Y767846D03*
X378868Y723311D03*
X421530Y814262D03*
X419186Y784430D03*
X429202Y894806D03*
X426858Y864974D03*
X382324Y863483D03*
X382963Y895871D03*
X365917Y880316D03*
X413927Y901690D03*
X397345Y857155D03*
X432682Y23909D03*
X472315Y23056D03*
X496393Y55871D03*
X457399Y46069D03*
X496109Y93412D03*
X457989Y78967D03*
X493200Y145500D03*
X451789Y154565D03*
X473097Y208901D03*
X453252Y250240D03*
X438300Y481200D03*
X434515Y483333D03*
X434412Y479334D03*
X432014Y476132D03*
X455846Y546626D03*
X465212Y726260D03*
X465851Y758648D03*
X437511Y759714D03*
X448805Y743093D03*
X435167Y729882D03*
X474587Y765253D03*
X445197Y719047D03*
X449231Y780808D03*
X449870Y813196D03*
X432824Y797641D03*
X476931Y795085D03*
X488225Y778464D03*
X499945Y828325D03*
X486307Y815114D03*
X456903Y861352D03*
X457542Y893740D03*
X440496Y878185D03*
X488651Y844946D03*
X499208Y899795D03*
X463674Y852891D03*
X557547Y24335D03*
X526213Y34431D03*
X555558Y100229D03*
X531425Y77545D03*
X545330Y147959D03*
X521476Y205704D03*
X509632Y174434D03*
X526688Y248818D03*
X566000Y536700D03*
X508224Y580873D03*
X549379Y653173D03*
X504632Y761631D03*
X505271Y794019D03*
X516352Y811492D03*
X562377Y833013D03*
X532332Y836635D03*
X516991Y843880D03*
X563016Y865401D03*
X534676Y866467D03*
X545970Y849846D03*
X545118Y880530D03*
X528711Y897363D03*
X515073Y884152D03*
X562590Y881808D03*
X510579Y854786D03*
X545757Y912918D03*
X517417Y913984D03*
X564934Y911640D03*
X573457Y59531D03*
X621826Y20111D03*
X591122Y33010D03*
X607704Y77545D03*
X586385Y204283D03*
X596334Y173012D03*
X602967Y248818D03*
X633923Y520400D03*
X587942Y582024D03*
X614582Y653599D03*
X604141Y675547D03*
X578784Y682152D03*
X582620Y653386D03*
X632693Y697281D03*
X607550Y703460D03*
X628006Y720720D03*
X592635Y878186D03*
X576228Y895019D03*
X640791Y876268D03*
X641430Y908656D03*
X613090Y909722D03*
X624384Y893101D03*
X610746Y879890D03*
X593274Y910574D03*
X660180Y56547D03*
X657451Y28746D03*
X703700Y30300D03*
X651658Y95968D03*
X692985Y75650D03*
X699619Y201914D03*
X652714Y200019D03*
X692512Y162589D03*
X661673Y260892D03*
X688248Y246923D03*
X712386Y297542D03*
X711500Y438300D03*
X694995Y453626D03*
X694923Y461253D03*
X694851Y469456D03*
X694907Y476993D03*
X644900Y538300D03*
X668135Y523360D03*
X672161Y528021D03*
X676550Y523677D03*
X672342Y519560D03*
X672257Y523769D03*
X678293Y698772D03*
X675736Y657222D03*
X694061Y681726D03*
X654641Y691101D03*
X643987Y664041D03*
X697897Y662763D03*
X708231Y730948D03*
X681276Y722211D03*
X650805Y716671D03*
X698962Y707936D03*
X692356Y875629D03*
X692995Y908017D03*
X664655Y909083D03*
X675949Y892462D03*
X662311Y879251D03*
X754800Y56800D03*
Y36800D03*
Y16800D03*
X723466Y60810D03*
X721334Y17767D03*
X754800Y76800D03*
X754700Y117600D03*
Y97600D03*
X734333Y88085D03*
X754700Y197600D03*
Y177600D03*
Y157600D03*
Y137600D03*
Y257600D03*
Y237600D03*
Y217600D03*
Y277600D03*
X753800Y303200D03*
X767300Y340400D03*
X766900Y333754D03*
X735134Y289819D03*
X767000Y410900D03*
X766700Y403500D03*
X766900Y395400D03*
Y387800D03*
Y364600D03*
Y356300D03*
X767600Y348500D03*
X767400Y481600D03*
Y465900D03*
X767500Y450800D03*
X767300Y441747D03*
X766500Y435100D03*
X766800Y427000D03*
X767100Y418700D03*
Y544600D03*
X766800Y535700D03*
X767200Y524500D03*
X766900Y497700D03*
X767200Y489700D03*
X767100Y623900D03*
Y614800D03*
X766700Y606900D03*
X767700Y600200D03*
X766700Y592700D03*
X767000Y584300D03*
Y576100D03*
Y569500D03*
X726000Y650700D03*
X720000Y650800D03*
X733000Y650600D03*
X740000D03*
X766900Y639500D03*
Y631900D03*
X715795Y697494D03*
X750300Y663000D03*
X740513Y687906D03*
X745733Y713048D03*
X764200Y813000D03*
X745413Y854763D03*
X716221Y876694D03*
X729859Y889905D03*
X718565Y906526D03*
X746905Y905460D03*
X746266Y873072D03*
G54D22*
G01X39800Y172900D02*
X29800D01*
X21600Y164700D01*
Y107679D01*
X22980Y106299D01*
G01X633923Y520400D02*
Y506077D01*
X653707Y486293D01*
X667979D01*
G01X711500Y438300D02*
X711100Y438700D01*
X699700D01*
X688460Y449940D01*
Y477869D01*
X680036Y486293D01*
X667979D01*
G54D13*
G01X-771361Y-182763D02*
Y-262763D01*
G01Y-218263D02*
X373639D01*
G01X-771361Y-262763D02*
X373639D01*
G01X-775361Y-166763D02*
G02I-12000J0D01*
G01X-780511D02*
G02I-6850J0D01*
G01X-787361Y-182763D02*
Y-150763D01*
G01X-771361Y-166763D02*
X-803361D01*
G01X-771361Y-182763D02*
X373639D01*
G01X-413861D02*
Y-262763D01*
G01X-276361Y-182763D02*
Y-262763D01*
G01X-161361Y-182763D02*
Y-262763D01*
G01X6139Y-182763D02*
Y-262763D01*
G01X74639Y441855D02*
X74858D01*
X77853Y438860D01*
X83952D01*
X86493Y441401D01*
G01X86687Y421669D02*
X83255D01*
X78811Y426113D01*
G01X94092Y492819D02*
X81106Y505805D01*
X61405D01*
X60800Y505200D01*
G01X106341Y426062D02*
X103710Y423431D01*
Y417090D01*
X105265Y415535D01*
X107768D01*
X110222Y417989D01*
G01X133864Y433783D02*
X109699D01*
G01X106263Y437583D02*
Y437219D01*
X109699Y433783D01*
G01X94263Y418129D02*
X94609D01*
X98363Y421883D01*
G01X110332Y425814D02*
Y433150D01*
X109699Y433783D01*
G01X106210Y421976D02*
X106494D01*
X110332Y425814D01*
G01X98363Y421883D02*
Y425845D01*
X102364Y429846D01*
G01D02*
Y433684D01*
X106263Y437583D01*
G01X102684Y445671D02*
Y441162D01*
X106263Y437583D01*
G01X86493Y441401D02*
X86616Y441278D01*
Y433783D01*
G01X180445Y422567D02*
X180121D01*
X178632Y421078D01*
X173319D01*
X171851Y422546D01*
Y430050D01*
X173315Y431514D01*
X175488D01*
X177661Y433687D01*
Y438188D01*
X174315Y441534D01*
Y451017D01*
X177097Y453799D01*
Y458400D01*
X180553Y461856D01*
Y487039D01*
X172250Y495342D01*
X120985D01*
X115504Y489861D01*
Y487175D01*
X119451Y483228D01*
Y464349D01*
X121017Y462783D01*
X126429Y457372D01*
X130080D01*
G01X176991Y463723D02*
X176195D01*
X175255Y462783D01*
X167837D01*
X166559Y464061D01*
X152879D01*
X150164Y461346D01*
X141827D01*
G01X145675Y425909D02*
X148788Y422796D01*
Y418974D01*
X161967Y405795D01*
X177235D01*
X179225Y403805D01*
Y403667D01*
G01X176139Y-182763D02*
Y-262763D01*
G01X177087Y178920D02*
Y174027D01*
X168093Y165033D01*
X165233D01*
X152350Y152150D01*
Y131084D01*
G01X251687Y98033D02*
X253464Y96256D01*
X253567D01*
X261830Y87993D01*
Y81230D01*
G01X373639Y-182763D02*
Y-262763D01*
G01X401639Y-166763D02*
G02I-12000J0D01*
G01X396489D02*
G02I-6850J0D01*
G01X389639Y-182763D02*
Y-150763D01*
G01X405639Y-166763D02*
X373639D01*
G01X362793Y126096D02*
Y77815D01*
G01X435138Y460661D02*
Y197164D01*
X364070Y126096D01*
X362793D01*
G01X381025Y120650D02*
Y73748D01*
G01X416588Y467839D02*
X403219Y454470D01*
Y173422D01*
X365281Y135484D01*
X365131D01*
G01X428343Y463067D02*
X432732D01*
X435138Y460661D01*
G01X707890Y467821D02*
X708059Y467652D01*
Y449951D01*
G01X682915Y467823D02*
Y449878D01*
X682774Y449737D01*
G01X684259Y476130D02*
X682915Y474786D01*
Y467823D01*
G01X684600Y542100D02*
Y538207D01*
X701140Y521667D01*
Y513560D01*
X723945Y490755D01*
Y459700D01*
X727100Y456545D01*
Y445900D01*
X723945Y442745D01*
Y121908D01*
X722687Y120650D01*
X8789Y376072D03*
X6944Y414616D03*
X6855Y436844D03*
X6750Y425868D03*
X7180Y449205D03*
X62439Y413744D03*
X66931Y398350D03*
X74863Y390483D03*
X64055Y389700D03*
X33722Y401639D03*
X74544Y414071D03*
X70779Y402387D03*
X79016Y410283D03*
X35738Y406956D03*
X14422Y411528D03*
X14657Y416838D03*
X10615Y411073D03*
X26551Y394546D03*
X30232Y416556D03*
X23922Y415548D03*
X35994Y410146D03*
X43719Y414419D03*
X32141Y407501D03*
X31808Y410684D03*
X18448Y402542D03*
X74817Y409752D03*
X26972Y399588D03*
X70882Y409794D03*
X66938Y410045D03*
X78939Y414083D03*
X18448Y406788D03*
X53976Y389814D03*
X74894Y398251D03*
X62031Y399713D03*
X70775Y398396D03*
X70845Y405839D03*
X70952Y414050D03*
X54515Y396433D03*
X54463Y386651D03*
X70865Y390502D03*
X74702Y394300D03*
X74869Y406315D03*
X78300Y386505D03*
X64948Y386626D03*
X78362Y398337D03*
X77963Y381183D03*
X70888Y394222D03*
X66963Y473083D03*
X66931Y484968D03*
X79081Y465348D03*
X70704Y429620D03*
X67015Y449433D03*
X74639Y441855D03*
X78754Y453353D03*
X78811Y426113D03*
X52151Y456887D03*
X66903Y457689D03*
X78798Y433983D03*
X17072Y435057D03*
X74836Y453477D03*
X59980Y482517D03*
X78754Y449904D03*
X67112Y481066D03*
X70488Y465291D03*
X74450Y457429D03*
X70713Y461504D03*
X36237Y441728D03*
X70908Y457771D03*
X70898Y418271D03*
X61038Y424878D03*
X74726Y425594D03*
X59209Y438908D03*
X46853Y441796D03*
X78561Y421756D03*
X70809Y438057D03*
X43659Y432766D03*
X43088Y438073D03*
X45486Y456341D03*
X38566Y451290D03*
X42312Y463368D03*
X74780Y429794D03*
X24357Y423051D03*
X37988Y438328D03*
X19757Y418538D03*
X29472Y428016D03*
X78738Y429679D03*
X11964Y421332D03*
X52476Y439395D03*
X13062Y429279D03*
X74656Y421838D03*
X17936Y431103D03*
X14206Y433632D03*
X15424Y422722D03*
X70857Y433857D03*
X19015Y426461D03*
X14147Y438989D03*
X74752Y437655D03*
X74437Y473159D03*
X15872Y441916D03*
X74460Y461287D03*
X78793Y445704D03*
X70868Y477094D03*
X23748Y436249D03*
X26611Y441743D03*
X70909Y469595D03*
X30513Y437850D03*
X74702Y469183D03*
X37420Y461517D03*
X31517Y445328D03*
X70868Y473157D03*
X28472Y447107D03*
X48298Y454813D03*
X70602Y453533D03*
X79050Y457367D03*
X74805Y481031D03*
X66991Y476766D03*
X62798Y461555D03*
X74451Y465323D03*
X79094Y441620D03*
X74801Y433368D03*
X70869Y421840D03*
X70759Y449277D03*
X74805Y477094D03*
X70868Y481031D03*
X74598Y485021D03*
X78421Y473078D03*
X74695Y449260D03*
X59063Y485583D03*
X79134Y461339D03*
X78742Y488905D03*
X66961Y488885D03*
X74805Y492842D03*
X74870Y488789D03*
X69523Y567387D03*
X69555Y564187D03*
X69569Y594959D03*
X69520Y560987D03*
X68421Y570392D03*
X69323Y579887D03*
X69518Y604727D03*
X69599Y601527D03*
X69569Y598159D03*
X69388Y576660D03*
X69450Y573460D03*
X69569Y608021D03*
X69496Y611417D03*
X69661Y591387D03*
X66579Y592250D03*
X63125Y592801D03*
X62681Y589462D03*
X69451Y684303D03*
Y681103D03*
X68928Y687846D03*
X69316Y697605D03*
X69451Y691003D03*
X69474Y694403D03*
X69523Y718313D03*
Y715113D03*
X69472Y729385D03*
X69548Y726185D03*
X69558Y711913D03*
X68620Y722610D03*
X106419Y310245D03*
X126184Y310860D03*
X93200Y308800D03*
X145771Y414191D03*
X82555Y406288D03*
X110472Y394496D03*
X145765Y406438D03*
X122053Y406224D03*
X114175Y410161D03*
X125990Y394413D03*
X141738D03*
X98427Y414098D03*
X125990D03*
X90553Y410161D03*
X102263Y414083D03*
X141887Y410202D03*
X102364Y406224D03*
X133864Y410161D03*
X94367Y394479D03*
X102364Y402287D03*
X106301Y398350D03*
Y402287D03*
X102364Y398350D03*
X110238Y402287D03*
X114175D03*
X110238Y398350D03*
X114175D03*
X85721Y385798D03*
X149362Y413951D03*
X149498Y406396D03*
X145795Y410173D03*
X149431Y394402D03*
X149783Y390487D03*
X110238Y410161D03*
X141738Y414098D03*
X133863Y413773D03*
X114175Y414098D03*
X122053D03*
X125990Y410161D03*
X94579Y406324D03*
X118130Y398511D03*
X98427Y410161D03*
X90553Y414098D03*
X86563Y402383D03*
X133964Y394555D03*
X102555Y394412D03*
X86616Y394413D03*
X86463Y390483D03*
X114175Y406224D03*
X126063Y406183D03*
X141738Y406224D03*
X106301D03*
X149663Y410083D03*
X82459Y413976D03*
X90566Y394383D03*
X82663Y402406D03*
X133864Y402287D03*
X86772Y414047D03*
X122053Y402287D03*
X133864Y398350D03*
X137801D03*
X122053D03*
X137801Y402287D03*
X125990D03*
Y398350D03*
X129927Y402287D03*
Y398350D03*
X82663Y398383D03*
X141738Y402287D03*
Y398350D03*
X145865Y402287D03*
Y398350D03*
X149488Y402114D03*
X149583Y398383D03*
X90359Y469275D03*
X137801Y453472D03*
Y445598D03*
X133864Y437720D03*
Y445598D03*
X133953Y425813D03*
X102684Y445671D03*
X106263Y437583D03*
X133864Y433783D03*
X102364Y429846D03*
X98363Y421883D03*
X94263Y418129D03*
X106210Y421976D03*
X110332Y425814D03*
X149612Y445598D03*
Y433783D03*
X86493Y441401D03*
X86616Y433783D03*
X86687Y421669D03*
X137801Y477094D03*
X149612D03*
X114175D03*
X102364D03*
X98626Y477049D03*
X130081Y425912D03*
X121943Y425834D03*
X114091Y425962D03*
X122053Y421972D03*
Y418035D03*
X106301D03*
X114175D03*
X133863Y417883D03*
X117951Y437592D03*
X114175Y445598D03*
X110263Y441683D03*
X118189Y445711D03*
X125990Y445598D03*
X110238Y437720D03*
X125990D03*
X110222Y417989D03*
X106341Y426062D03*
X82564Y449659D03*
X145663Y441483D03*
X98288Y441609D03*
X149612Y429846D03*
X110238Y453472D03*
X122053Y429846D03*
X114063Y429879D03*
X125897Y453240D03*
X118238Y453417D03*
X149594Y480923D03*
X94518Y449186D03*
X86768Y449383D03*
X98427Y484968D03*
Y481031D03*
X102364D03*
Y484968D03*
X106301D03*
Y481031D03*
X114175Y484968D03*
Y481031D03*
X122053Y484968D03*
Y481031D03*
X125990Y484968D03*
Y481031D03*
X145567Y453547D03*
X145763Y449583D03*
X149576Y465497D03*
X98597Y457291D03*
X94490Y429846D03*
X90463Y425983D03*
X90480Y437608D03*
X82562Y425980D03*
X86505Y425987D03*
X90380Y429650D03*
X130080Y457372D03*
X94490Y437720D03*
X82681Y430041D03*
X141827Y461346D03*
X98334Y429754D03*
X98427Y437720D03*
X94369Y425977D03*
X82677Y433595D03*
X149563Y469220D03*
X94490Y433783D03*
X141738Y481031D03*
X82663Y457486D03*
X141738Y484968D03*
X98433Y449125D03*
X137801Y481031D03*
X102600Y425983D03*
X137801Y484968D03*
X94554Y421911D03*
X133864Y481031D03*
X149612Y437720D03*
X94414Y445605D03*
X133864Y484968D03*
X86663Y429536D03*
X82542Y445403D03*
X98427Y433783D03*
X86568Y445669D03*
X90426Y449431D03*
X90563Y417983D03*
X145675Y425909D03*
X82573Y441360D03*
X145675Y437720D03*
X98280Y445405D03*
X90426Y441880D03*
X145675Y481031D03*
Y484968D03*
X145737Y418077D03*
X145675Y473157D03*
Y465283D03*
X149719Y457328D03*
X129927Y473157D03*
Y465283D03*
X137801Y461346D03*
Y457409D03*
X114175Y473157D03*
X122053Y469220D03*
X110263Y469083D03*
X122053Y473157D03*
X90350Y473069D03*
X82679Y477094D03*
X90662Y461604D03*
X106263Y453483D03*
X106449Y465157D03*
X122053Y445598D03*
X126180Y418224D03*
X137801Y437720D03*
X137767Y425993D03*
X129927Y445598D03*
X141738Y449535D03*
X133864Y421972D03*
Y429846D03*
X98533Y418180D03*
X118134Y449362D03*
X106363Y441583D03*
X110238Y445598D03*
X110289Y422113D03*
X122053Y437720D03*
X114175D03*
X94661Y441681D03*
X106263Y433683D03*
X90544Y433408D03*
X90408Y421930D03*
X129927Y437720D03*
X141738Y429846D03*
X86663Y453583D03*
X82732Y453139D03*
X102227Y473344D03*
X145675Y469220D03*
X90376Y476918D03*
X110238Y477094D03*
X141738D03*
X137801Y473157D03*
X98427Y469046D03*
X106301Y469220D03*
X114175D03*
X126057Y469287D03*
X129927Y469220D03*
X137801D03*
X122053Y465283D03*
X133864D03*
X106301Y461346D03*
X122113Y457535D03*
X129963Y461283D03*
X110263Y457283D03*
X122158Y453388D03*
X125990Y477094D03*
X137801Y449535D03*
X149612Y425909D03*
X82535Y461227D03*
X83021Y473118D03*
X141595Y421932D03*
X141775Y426153D03*
X86735Y461382D03*
X141763Y437883D03*
X86937Y477160D03*
X141682Y417902D03*
X82759Y469436D03*
X145663Y445583D03*
X145675Y429846D03*
X142008Y457429D03*
X141863Y445583D03*
X86959Y469276D03*
X137570Y421843D03*
X145561Y421879D03*
X90965Y465270D03*
X129927Y481031D03*
Y484968D03*
X110238Y481031D03*
Y484968D03*
X94490Y481031D03*
X86663Y457283D03*
X94490Y484968D03*
X86765Y465205D03*
X138061Y418151D03*
X145675Y433783D03*
X82763Y417750D03*
X86523Y417943D03*
X94844Y469182D03*
X102469Y469134D03*
X106149Y457371D03*
X141649Y453189D03*
X149620Y485149D03*
X98682Y461441D03*
X94092Y492819D03*
X141738Y488905D03*
X110238D03*
X125990D03*
X94377Y489070D03*
X118004Y488825D03*
X133864Y488905D03*
X149612D03*
X102308Y488978D03*
X86616Y488905D03*
X91852Y563129D03*
X91156Y572112D03*
X90823Y581387D03*
X91343Y598284D03*
X91023Y606587D03*
X90923Y616187D03*
X91198Y595087D03*
X91123Y591887D03*
X91223Y588487D03*
X159768Y238444D03*
X160004Y233894D03*
X181576Y407810D03*
X175463Y413760D03*
X161499Y402554D03*
X169297Y402536D03*
X157502Y390427D03*
X173425Y390228D03*
X214660Y362600D03*
X176751Y387090D03*
X157251Y414149D03*
X161477Y394511D03*
X180991Y398678D03*
X180809Y414170D03*
X179225Y403667D03*
X203410Y394323D03*
X182378Y390377D03*
X157574Y394185D03*
X161241Y398226D03*
X161277Y414114D03*
X174124Y402624D03*
X161213Y390551D03*
X169503Y386977D03*
X153587Y406496D03*
X157554Y402251D03*
X157698Y406313D03*
X161475Y410299D03*
X165266Y409882D03*
X165337Y414489D03*
X153528Y410052D03*
X165455Y398256D03*
X165229Y402019D03*
X157411Y398513D03*
X169113Y398299D03*
X178031Y390023D03*
X177588Y482616D03*
X161423Y469220D03*
X153583Y461058D03*
X169297Y477094D03*
Y465283D03*
X157486Y437720D03*
Y429846D03*
X153416Y445539D03*
X169290Y417960D03*
X169297Y437720D03*
X169112Y453260D03*
X169166Y429679D03*
X153549Y429846D03*
X165621Y418066D03*
X153549Y425909D03*
X161746Y421972D03*
X177182Y467018D03*
X175477Y472360D03*
X176815Y479061D03*
X161473Y457213D03*
X165360Y477094D03*
X153549Y437720D03*
X157560Y445484D03*
X153549Y449535D03*
X174859Y469220D03*
X157322Y453385D03*
X165317Y461561D03*
X165360Y473157D03*
X161455Y453385D03*
X177763Y486293D03*
X153463Y453383D03*
X157411Y469344D03*
X161423Y477094D03*
X157486Y461346D03*
X153690Y469111D03*
X165411Y429590D03*
X175161Y434723D03*
X161423Y445598D03*
X153549Y421972D03*
X161423Y484968D03*
Y481031D03*
X157486Y473157D03*
X165360Y469220D03*
X153549Y477094D03*
X173234Y465283D03*
Y453472D03*
X174086Y484839D03*
X175150Y476294D03*
X174351Y429014D03*
X161423Y437720D03*
X153549Y433783D03*
X161363Y425780D03*
X173234Y437720D03*
X173155Y417978D03*
X153422Y441722D03*
X161423Y449430D03*
X153549Y473157D03*
X161670Y418161D03*
X176662Y418122D03*
X153201Y418097D03*
X157401Y418143D03*
X157463Y421883D03*
X157486Y425909D03*
X173458Y457178D03*
X178053Y474260D03*
X174601Y481467D03*
X165319Y453134D03*
X165353Y480812D03*
X157486Y433783D03*
X165360Y421972D03*
X153646Y457393D03*
X161294Y461561D03*
X165363Y425783D03*
X157393Y457572D03*
X165217Y457361D03*
X165355Y433382D03*
X161423Y473157D03*
X165355Y437582D03*
X165360Y445598D03*
X157411Y449556D03*
X169157Y445598D03*
X157508Y480990D03*
X165288Y449306D03*
X157486Y484968D03*
X153601Y480894D03*
X153586Y485118D03*
X161423Y433783D03*
X181414Y490281D03*
X174475Y488016D03*
X178084Y493198D03*
X157486Y488905D03*
X165360D03*
X169297Y492842D03*
X161423D03*
X159589Y817543D03*
X157422Y825918D03*
X158725Y835536D03*
X159688Y832484D03*
X159431Y838974D03*
X159688Y829234D03*
X159137Y820712D03*
X160735Y857183D03*
X154730Y847010D03*
X159688Y851564D03*
X159560Y842172D03*
X159426Y848357D03*
X651000Y467700D03*
X646163Y482677D03*
X643296Y477617D03*
X643914Y470592D03*
X648652Y470028D03*
X654990Y463513D03*
X658399Y460842D03*
X659485Y455066D03*
X666818Y452921D03*
X710645Y447266D03*
X678767Y447136D03*
X672583Y467901D03*
X667831Y479556D03*
X662166Y456914D03*
X661760Y460089D03*
X646246Y475961D03*
X646794Y472634D03*
X682915Y467823D03*
X708059Y449951D03*
X671145Y454348D03*
X658195Y464248D03*
X653351Y470098D03*
X650837Y472421D03*
X646251Y479161D03*
X675745Y448189D03*
X685815Y496140D03*
X689996Y496274D03*
X694169Y496394D03*
X698475Y496387D03*
X702670Y496148D03*
X707296Y496348D03*
X716700Y445400D03*
X742200Y472500D03*
X724300Y454000D03*
X719100Y478900D03*
X744986Y481255D03*
X749974Y477780D03*
X749628Y471196D03*
X739751Y469686D03*
X735295Y463720D03*
X738636Y457903D03*
X731780Y452531D03*
X729478Y459116D03*
X721600Y451000D03*
X719700Y485600D03*
X735191Y453967D03*
X735231Y457167D03*
X746845Y476389D03*
Y473189D03*
X717993Y451389D03*
X731751Y464398D03*
X735259Y469898D03*
X721445Y455789D03*
X726589Y460909D03*
X743520Y478297D03*
X738745Y472789D03*
X713845Y447289D03*
G54D23*
G01X6614Y549842D02*
Y553544D01*
G01D02*
Y557246D01*
G01Y553544D02*
X10316D01*
G01X6849Y623622D02*
X10551D01*
G01X6614Y667952D02*
Y671654D01*
G01D02*
Y675356D01*
G01Y671654D02*
X10316D01*
G01X6849Y741732D02*
X10551D01*
G01X76772Y7633D02*
Y19685D01*
G01D02*
Y31737D01*
G01X64720Y19685D02*
X76772D01*
G01D02*
X88824D01*
G01X29528Y7633D02*
Y19685D01*
G01D02*
Y31737D01*
G01X17476Y19685D02*
X29528D01*
G01D02*
X41580D01*
G01X30854Y106299D02*
Y110201D01*
G01Y106299D02*
X34756D01*
G01X32204Y549842D02*
Y553544D01*
G01D02*
Y557246D01*
G01X28502Y553544D02*
X32204D01*
G01D02*
X35906D01*
G01X18425Y549842D02*
Y553544D01*
G01D02*
Y557246D01*
G01X14723Y553544D02*
X18425D01*
G01D02*
X22127D01*
G01X32204Y619920D02*
Y623622D01*
G01D02*
Y627324D01*
G01X28502Y623622D02*
X32204D01*
G01D02*
X35906D01*
G01X18425Y619920D02*
Y623622D01*
G01D02*
Y627324D01*
G01X14723Y623622D02*
X18425D01*
G01D02*
X22127D01*
G01X10551Y619920D02*
Y623622D01*
G01D02*
Y627324D01*
G01Y623622D02*
X14253D01*
G01X32204Y667952D02*
Y671654D01*
G01D02*
Y675356D01*
G01X28502Y671654D02*
X32204D01*
G01D02*
X35906D01*
G01X18425Y667952D02*
Y671654D01*
G01D02*
Y675356D01*
G01X14723Y671654D02*
X18425D01*
G01D02*
X22127D01*
G01X32204Y738030D02*
Y741732D01*
G01D02*
Y745434D01*
G01X28502Y741732D02*
X32204D01*
G01D02*
X35906D01*
G01X18425Y738030D02*
Y741732D01*
G01D02*
Y745434D01*
G01X14723Y741732D02*
X18425D01*
G01D02*
X22127D01*
G01X10551Y738030D02*
Y741732D01*
G01D02*
Y745434D01*
G01Y741732D02*
X14253D01*
G01X109410Y789679D02*
Y796831D01*
G01D02*
Y803983D01*
G01X102258Y796831D02*
X109410D01*
G01D02*
X116562D01*
G01X143460Y905512D02*
X155512D01*
G01X108268Y893460D02*
Y905512D01*
G01D02*
Y917564D01*
G01X96216Y905512D02*
X108268D01*
G01D02*
X120320D01*
G01X109410Y869245D02*
Y876397D01*
G01D02*
Y883549D01*
G01X102258Y876397D02*
X109410D01*
G01D02*
X116562D01*
G01X182681Y560832D02*
Y564984D01*
G01Y560832D02*
X186833D01*
G01X182681Y576680D02*
Y580832D01*
G01D02*
Y584984D01*
G01X178529Y580832D02*
X182681D01*
G01D02*
X186833D01*
G01X168465Y789679D02*
Y796831D01*
G01D02*
Y803983D01*
G01X161313Y796831D02*
X168465D01*
G01D02*
X175617D01*
G01X168465Y869245D02*
Y876397D01*
G01D02*
Y883549D01*
G01X161313Y876397D02*
X168465D01*
G01D02*
X175617D01*
G01X155512Y893460D02*
Y905512D01*
G01D02*
Y917564D01*
G01Y905512D02*
X167564D01*
G01X286982Y823883D02*
Y828335D01*
G01D02*
Y832787D01*
G01X282530Y828335D02*
X286982D01*
G01D02*
X291434D01*
G01X296982Y823883D02*
Y828335D01*
G01D02*
Y832787D01*
G01X292530Y828335D02*
X296982D01*
G01D02*
X301434D01*
G01X306982Y823883D02*
Y828335D01*
G01D02*
Y832787D01*
G01X302530Y828335D02*
X306982D01*
G01D02*
X311434D01*
G01X316982Y823883D02*
Y828335D01*
G01D02*
Y832787D01*
G01X312530Y828335D02*
X316982D01*
G01D02*
X321434D01*
G01X326982Y823883D02*
Y828335D01*
G01D02*
Y832787D01*
G01X322530Y828335D02*
X326982D01*
G01D02*
X331434D01*
G01X336982Y823883D02*
Y828335D01*
G01D02*
Y832787D01*
G01X332530Y828335D02*
X336982D01*
G01D02*
X341434D01*
G01X346982Y823883D02*
Y828335D01*
G01D02*
Y832787D01*
G01X342530Y828335D02*
X346982D01*
G01D02*
X351434D01*
G01X356982Y823883D02*
Y828335D01*
G01D02*
Y832787D01*
G01X352530Y828335D02*
X356982D01*
G01D02*
X361434D01*
G01X366982Y823883D02*
Y828335D01*
G01D02*
Y832787D01*
G01X362530Y828335D02*
X366982D01*
G01D02*
X371434D01*
G54D14*
X6614Y553544D03*
X10551Y623622D03*
X6614Y671654D03*
X10551Y741732D03*
X18425Y553544D03*
X32204D03*
X18425Y623622D03*
X32204D03*
X18425Y671654D03*
X32204D03*
X18425Y741732D03*
X32204D03*
G54D24*
G01X-755164Y-252763D02*
Y-235263D01*
G01X-746868D02*
X-755164Y-246055D01*
G01X-745558Y-252763D02*
X-751453Y-241097D01*
G01X-737883Y-252763D02*
Y-235263D01*
X-727839Y-252763D01*
Y-235263D01*
G01X-715361Y-252763D02*
X-717108Y-252471D01*
X-718636Y-251305D01*
X-719946Y-249555D01*
X-720820Y-247513D01*
X-721256Y-245180D01*
Y-242846D01*
X-720820Y-240513D01*
X-719946Y-238471D01*
X-718636Y-236722D01*
X-717108Y-235555D01*
X-715361Y-235263D01*
X-713615Y-235555D01*
X-712086Y-236722D01*
X-710776Y-238471D01*
X-709902Y-240513D01*
X-709466Y-242846D01*
Y-245180D01*
X-709902Y-247513D01*
X-710776Y-249555D01*
X-712086Y-251305D01*
X-713615Y-252471D01*
X-715361Y-252763D01*
G01X-702446D02*
X-693276Y-235263D01*
G01X-702446D02*
X-693276Y-252763D01*
G01X-658494D02*
X-667228D01*
Y-235263D01*
X-658494D01*
G01X-661988Y-243721D02*
X-667228D01*
G01X-649946Y-252763D02*
X-640776Y-235263D01*
G01X-649946D02*
X-640776Y-252763D01*
G01X-632228D02*
Y-235263D01*
X-626988D01*
X-625241Y-236138D01*
X-623931Y-238180D01*
X-623494Y-240513D01*
X-623931Y-242846D01*
X-625023Y-244596D01*
X-626988Y-245472D01*
X-632228D01*
G01X-615820Y-252763D02*
X-610361Y-235263D01*
X-604902Y-252763D01*
G01X-606868Y-246638D02*
X-613855D01*
G01X-597883Y-252763D02*
Y-235263D01*
X-587839Y-252763D01*
Y-235263D01*
G01X-580164Y-252763D02*
Y-235263D01*
X-575798D01*
X-574051Y-236138D01*
X-572741Y-237305D01*
X-571649Y-239054D01*
X-570776Y-241097D01*
X-570558Y-244013D01*
X-570776Y-246930D01*
X-571649Y-248972D01*
X-572741Y-250722D01*
X-574051Y-251888D01*
X-575798Y-252763D01*
X-580164D01*
G01X-553494D02*
X-562228D01*
Y-235263D01*
X-553494D01*
G01X-556988Y-243721D02*
X-562228D01*
G01X-544728Y-252763D02*
Y-235263D01*
X-539269D01*
X-537523Y-236138D01*
X-536431Y-237305D01*
X-535994Y-239638D01*
X-536431Y-241972D01*
X-537741Y-243430D01*
X-539269Y-244305D01*
X-544728D01*
G01X-539269D02*
X-535994Y-252763D01*
G01X-503615Y-243430D02*
X-502741Y-242555D01*
X-502086Y-241097D01*
X-501649Y-239054D01*
X-502086Y-237305D01*
X-502959Y-236138D01*
X-504488Y-235263D01*
X-510383D01*
Y-252763D01*
X-503178D01*
X-501649Y-251597D01*
X-500776Y-249846D01*
X-500339Y-247805D01*
X-500776Y-245763D01*
X-502086Y-244013D01*
X-503615Y-243430D01*
X-510383D01*
G01X-487861Y-252763D02*
X-489608Y-252471D01*
X-491136Y-251305D01*
X-492446Y-249555D01*
X-493320Y-247513D01*
X-493756Y-245180D01*
Y-242846D01*
X-493320Y-240513D01*
X-492446Y-238471D01*
X-491136Y-236722D01*
X-489608Y-235555D01*
X-487861Y-235263D01*
X-486115Y-235555D01*
X-484586Y-236722D01*
X-483276Y-238471D01*
X-482402Y-240513D01*
X-481966Y-242846D01*
Y-245180D01*
X-482402Y-247513D01*
X-483276Y-249555D01*
X-484586Y-251305D01*
X-486115Y-252471D01*
X-487861Y-252763D01*
G01X-475820D02*
X-470361Y-235263D01*
X-464902Y-252763D01*
G01X-466868Y-246638D02*
X-473855D01*
G01X-457228Y-252763D02*
Y-235263D01*
X-451769D01*
X-450023Y-236138D01*
X-448931Y-237305D01*
X-448494Y-239638D01*
X-448931Y-241972D01*
X-450241Y-243430D01*
X-451769Y-244305D01*
X-457228D01*
G01X-451769D02*
X-448494Y-252763D01*
G01X-440164D02*
Y-235263D01*
X-435798D01*
X-434051Y-236138D01*
X-432741Y-237305D01*
X-431649Y-239054D01*
X-430776Y-241097D01*
X-430558Y-244013D01*
X-430776Y-246930D01*
X-431649Y-248972D01*
X-432741Y-250722D01*
X-434051Y-251888D01*
X-435798Y-252763D01*
X-440164D01*
G01X-633538Y-207763D02*
Y-190263D01*
X-627861Y-204846D01*
X-622184Y-190263D01*
Y-207763D01*
G01X-610361D02*
X-611671Y-207471D01*
X-612981Y-206305D01*
X-613855Y-204263D01*
X-614291Y-201930D01*
X-613855Y-199596D01*
X-612981Y-197555D01*
X-611671Y-196388D01*
X-610361Y-196097D01*
X-609051Y-196388D01*
X-607741Y-197555D01*
X-606868Y-199596D01*
X-606649Y-201930D01*
X-606868Y-204263D01*
X-607741Y-206305D01*
X-609051Y-207471D01*
X-610361Y-207763D01*
G01X-588931Y-190263D02*
Y-207763D01*
G01Y-205139D02*
X-589804Y-206597D01*
X-591115Y-207471D01*
X-592643Y-207763D01*
X-594389Y-207180D01*
X-595699Y-205722D01*
X-596573Y-203972D01*
X-596791Y-201930D01*
X-596573Y-199888D01*
X-595699Y-198138D01*
X-594389Y-196680D01*
X-592643Y-196097D01*
X-591115Y-196388D01*
X-590023Y-196972D01*
X-588931Y-198138D01*
G01X-578636Y-199888D02*
X-571649D01*
X-572304Y-197846D01*
X-573396Y-196680D01*
X-574924Y-196097D01*
X-576453Y-196388D01*
X-577763Y-197263D01*
X-578636Y-199305D01*
X-579073Y-201055D01*
Y-202805D01*
X-578636Y-204555D01*
X-577544Y-206305D01*
X-576234Y-207471D01*
X-574706Y-207763D01*
X-573178Y-207180D01*
X-571649Y-205430D01*
G01X-557861Y-207763D02*
Y-190263D01*
G01X-380161Y-252763D02*
Y-235263D01*
X-382781Y-238763D01*
G01Y-252763D02*
X-377541D01*
G01X-366809Y-238180D02*
X-365499Y-236430D01*
X-363971Y-235555D01*
X-362224Y-235263D01*
X-360041Y-235846D01*
X-358513Y-237305D01*
X-358076Y-239054D01*
X-358294Y-240805D01*
X-359168Y-242263D01*
X-363534Y-245180D01*
X-365499Y-247221D01*
X-366809Y-250139D01*
X-367246Y-252763D01*
X-358076D01*
G01X-345161Y-235263D02*
X-346908Y-235846D01*
X-348218Y-237305D01*
X-349091Y-239054D01*
X-349746Y-241388D01*
X-349964Y-244013D01*
X-349746Y-246638D01*
X-349091Y-248972D01*
X-348218Y-250722D01*
X-346908Y-252180D01*
X-345161Y-252763D01*
X-343415Y-252180D01*
X-342104Y-250722D01*
X-341231Y-248972D01*
X-340576Y-246638D01*
X-340358Y-244013D01*
X-340576Y-241388D01*
X-341231Y-239054D01*
X-342104Y-237305D01*
X-343415Y-235846D01*
X-345161Y-235263D01*
G01X-327661D02*
X-329408Y-235846D01*
X-330718Y-237305D01*
X-331591Y-239054D01*
X-332246Y-241388D01*
X-332464Y-244013D01*
X-332246Y-246638D01*
X-331591Y-248972D01*
X-330718Y-250722D01*
X-329408Y-252180D01*
X-327661Y-252763D01*
X-325915Y-252180D01*
X-324604Y-250722D01*
X-323731Y-248972D01*
X-323076Y-246638D01*
X-322858Y-244013D01*
X-323076Y-241388D01*
X-323731Y-239054D01*
X-324604Y-237305D01*
X-325915Y-235846D01*
X-327661Y-235263D01*
G01X-307541Y-252763D02*
Y-235263D01*
X-315620Y-247805D01*
X-304702D01*
G01X-393278Y-207763D02*
Y-190263D01*
X-388038D01*
X-386291Y-191138D01*
X-384981Y-193180D01*
X-384544Y-195513D01*
X-384981Y-197846D01*
X-386073Y-199596D01*
X-388038Y-200472D01*
X-393278D01*
G01X-366608Y-191722D02*
X-367918Y-190846D01*
X-369446Y-190263D01*
X-371193D01*
X-373158Y-191138D01*
X-374686Y-192596D01*
X-375778Y-194347D01*
X-376651Y-197263D01*
X-376870Y-199888D01*
X-376433Y-202513D01*
X-375778Y-204263D01*
X-374468Y-206013D01*
X-372939Y-207180D01*
X-371411Y-207763D01*
X-369883D01*
X-368354Y-207180D01*
X-367044Y-206305D01*
X-365952Y-205139D01*
G01X-352165Y-198430D02*
X-351291Y-197555D01*
X-350636Y-196097D01*
X-350199Y-194054D01*
X-350636Y-192305D01*
X-351509Y-191138D01*
X-353038Y-190263D01*
X-358933D01*
Y-207763D01*
X-351728D01*
X-350199Y-206597D01*
X-349326Y-204846D01*
X-348889Y-202805D01*
X-349326Y-200763D01*
X-350636Y-199013D01*
X-352165Y-198430D01*
X-358933D01*
G01X-342961Y-213596D02*
X-329861D01*
G01X-323933Y-207763D02*
Y-190263D01*
X-313889Y-207763D01*
Y-190263D01*
G01X-301411Y-207763D02*
X-303158Y-207471D01*
X-304686Y-206305D01*
X-305996Y-204555D01*
X-306870Y-202513D01*
X-307306Y-200180D01*
Y-197846D01*
X-306870Y-195513D01*
X-305996Y-193471D01*
X-304686Y-191722D01*
X-303158Y-190555D01*
X-301411Y-190263D01*
X-299665Y-190555D01*
X-298136Y-191722D01*
X-296826Y-193471D01*
X-295952Y-195513D01*
X-295516Y-197846D01*
Y-200180D01*
X-295952Y-202513D01*
X-296826Y-204555D01*
X-298136Y-206305D01*
X-299665Y-207471D01*
X-301411Y-207763D01*
G01X-218861Y-252763D02*
Y-235263D01*
X-221481Y-238763D01*
G01Y-252763D02*
X-216241D01*
G01X-250570Y-190263D02*
X-245111Y-207763D01*
X-239652Y-190263D01*
G01X-223244Y-207763D02*
X-231978D01*
Y-190263D01*
X-223244D01*
G01X-226738Y-198721D02*
X-231978D01*
G01X-214478Y-207763D02*
Y-190263D01*
X-209019D01*
X-207273Y-191138D01*
X-206181Y-192305D01*
X-205744Y-194638D01*
X-206181Y-196972D01*
X-207491Y-198430D01*
X-209019Y-199305D01*
X-214478D01*
G01X-209019D02*
X-205744Y-207763D01*
G01X-192611Y-208346D02*
X-193048Y-208055D01*
Y-207471D01*
X-192611Y-207180D01*
X-192174Y-207471D01*
Y-208055D01*
X-192611Y-208346D01*
G01X-90778Y-235263D02*
Y-252763D01*
X-82044D01*
G01X-73714Y-249263D02*
X-72405Y-251305D01*
X-70658Y-252471D01*
X-68693Y-252763D01*
X-66946Y-252471D01*
X-65199Y-251013D01*
X-64108Y-249263D01*
X-63889Y-247513D01*
X-64326Y-245472D01*
X-65854Y-244013D01*
X-67383Y-243430D01*
X-69348D01*
G01X-67383D02*
X-66073Y-242555D01*
X-64981Y-241097D01*
X-64544Y-239347D01*
X-64981Y-237596D01*
X-66073Y-236138D01*
X-68038Y-235263D01*
X-70003Y-235555D01*
X-71968Y-236722D01*
G01X-125778Y-190263D02*
Y-207763D01*
X-117044D01*
G01X-99981D02*
Y-196097D01*
G01Y-198138D02*
X-100854Y-196972D01*
X-102165Y-196388D01*
X-103693Y-196097D01*
X-105221Y-196680D01*
X-106531Y-197846D01*
X-107405Y-199596D01*
X-107841Y-201930D01*
X-107405Y-204263D01*
X-106531Y-206013D01*
X-105221Y-207180D01*
X-103693Y-207763D01*
X-102165Y-207471D01*
X-100854Y-206597D01*
X-99981Y-205430D01*
G01X-90996Y-213013D02*
X-89686Y-213596D01*
X-87939Y-213013D01*
X-86848Y-211847D01*
X-85974Y-210388D01*
X-84665Y-205722D01*
X-81826Y-196097D01*
G01X-88813D02*
X-84665Y-205722D01*
G01X-72186Y-199888D02*
X-65199D01*
X-65854Y-197846D01*
X-66946Y-196680D01*
X-68474Y-196097D01*
X-70003Y-196388D01*
X-71313Y-197263D01*
X-72186Y-199305D01*
X-72623Y-201055D01*
Y-202805D01*
X-72186Y-204555D01*
X-71094Y-206305D01*
X-69784Y-207471D01*
X-68256Y-207763D01*
X-66728Y-207180D01*
X-65199Y-205430D01*
G01X-54468Y-207763D02*
Y-196097D01*
G01Y-198430D02*
X-53376Y-197263D01*
X-52284Y-196388D01*
X-50756Y-196097D01*
X-49665Y-196388D01*
X-48354Y-197263D01*
G01X-37186Y-205722D02*
X-36094Y-206888D01*
X-34566Y-207763D01*
X-33256D01*
X-31946Y-207180D01*
X-31073Y-206305D01*
X-30636Y-205139D01*
X-30854Y-203388D01*
X-31728Y-202513D01*
X-35658Y-200763D01*
X-36531Y-198721D01*
X-36094Y-197263D01*
X-35221Y-196388D01*
X-33911Y-196097D01*
X-32601Y-196388D01*
X-31291Y-197263D01*
G01X51772Y-235263D02*
Y-252763D01*
X60506D01*
G01X68836Y-235263D02*
Y-247805D01*
X69709Y-250430D01*
X71456Y-252180D01*
X73639Y-252763D01*
X75822Y-252180D01*
X77569Y-250430D01*
X78442Y-247805D01*
Y-235263D01*
G01X95942Y-236722D02*
X94632Y-235846D01*
X93104Y-235263D01*
X91357D01*
X89392Y-236138D01*
X87864Y-237596D01*
X86772Y-239347D01*
X85899Y-242263D01*
X85680Y-244888D01*
X86117Y-247513D01*
X86772Y-249263D01*
X88082Y-251013D01*
X89611Y-252180D01*
X91139Y-252763D01*
X92667D01*
X94196Y-252180D01*
X95506Y-251305D01*
X96598Y-250139D01*
G01X103836Y-252763D02*
Y-235263D01*
G01X112132D02*
X103836Y-246055D01*
G01X113442Y-252763D02*
X107547Y-241097D01*
G01X126139Y-252763D02*
Y-244888D01*
X121772Y-235263D01*
G01X130506D02*
X126139Y-244888D01*
G01X25086Y-207763D02*
Y-190263D01*
X29452D01*
X31199Y-191138D01*
X32509Y-192305D01*
X33601Y-194054D01*
X34474Y-196097D01*
X34692Y-199013D01*
X34474Y-201930D01*
X33601Y-203972D01*
X32509Y-205722D01*
X31199Y-206888D01*
X29452Y-207763D01*
X25086D01*
G01X44114Y-199888D02*
X51101D01*
X50446Y-197846D01*
X49354Y-196680D01*
X47826Y-196097D01*
X46297Y-196388D01*
X44987Y-197263D01*
X44114Y-199305D01*
X43677Y-201055D01*
Y-202805D01*
X44114Y-204555D01*
X45206Y-206305D01*
X46516Y-207471D01*
X48044Y-207763D01*
X49572Y-207180D01*
X51101Y-205430D01*
G01X61614Y-205722D02*
X62706Y-206888D01*
X64234Y-207763D01*
X65544D01*
X66854Y-207180D01*
X67727Y-206305D01*
X68164Y-205139D01*
X67946Y-203388D01*
X67072Y-202513D01*
X63142Y-200763D01*
X62269Y-198721D01*
X62706Y-197263D01*
X63579Y-196388D01*
X64889Y-196097D01*
X66199Y-196388D01*
X67509Y-197263D01*
G01X82389Y-196097D02*
Y-207763D01*
G01Y-191430D02*
X81952Y-191138D01*
Y-190555D01*
X82389Y-190263D01*
X82826Y-190555D01*
Y-191138D01*
X82389Y-191430D01*
G01X96832Y-212138D02*
X98361Y-213305D01*
X100107Y-213596D01*
X101635Y-213305D01*
X102946Y-211847D01*
X103819Y-209805D01*
Y-196097D01*
G01Y-198430D02*
X102946Y-197263D01*
X101635Y-196388D01*
X100107Y-196097D01*
X98361Y-196680D01*
X97269Y-197846D01*
X96395Y-199888D01*
X95959Y-201930D01*
X96177Y-203680D01*
X97051Y-205722D01*
X98361Y-207180D01*
X100107Y-207763D01*
X101417Y-207471D01*
X102946Y-206305D01*
X103819Y-205139D01*
G01X113677Y-207763D02*
Y-196097D01*
G01Y-199013D02*
X114551Y-197555D01*
X115861Y-196388D01*
X117607Y-196097D01*
X119135Y-196388D01*
X120446Y-197555D01*
X121101Y-199596D01*
Y-207763D01*
G01X131614Y-199888D02*
X138601D01*
X137946Y-197846D01*
X136854Y-196680D01*
X135326Y-196097D01*
X133797Y-196388D01*
X132487Y-197263D01*
X131614Y-199305D01*
X131177Y-201055D01*
Y-202805D01*
X131614Y-204555D01*
X132706Y-206305D01*
X134016Y-207471D01*
X135544Y-207763D01*
X137072Y-207180D01*
X138601Y-205430D01*
G01X149332Y-207763D02*
Y-196097D01*
G01Y-198430D02*
X150424Y-197263D01*
X151516Y-196388D01*
X153044Y-196097D01*
X154135Y-196388D01*
X155446Y-197263D01*
G01X196089Y-252763D02*
Y-235263D01*
X193469Y-238763D01*
G01Y-252763D02*
X198709D01*
G01X213589Y-235263D02*
X211842Y-235846D01*
X210532Y-237305D01*
X209659Y-239054D01*
X209004Y-241388D01*
X208786Y-244013D01*
X209004Y-246638D01*
X209659Y-248972D01*
X210532Y-250722D01*
X211842Y-252180D01*
X213589Y-252763D01*
X215335Y-252180D01*
X216646Y-250722D01*
X217519Y-248972D01*
X218174Y-246638D01*
X218392Y-244013D01*
X218174Y-241388D01*
X217519Y-239054D01*
X216646Y-237305D01*
X215335Y-235846D01*
X213589Y-235263D01*
G01X227159Y-253346D02*
X235019Y-235263D01*
G01X248589Y-252763D02*
Y-235263D01*
X245969Y-238763D01*
G01Y-252763D02*
X251209D01*
G01X261941Y-245472D02*
X263469Y-243430D01*
X264779Y-242263D01*
X266526Y-241680D01*
X268054Y-242263D01*
X269146Y-243430D01*
X270019Y-245180D01*
X270237Y-247221D01*
X270019Y-248972D01*
X269146Y-250722D01*
X267835Y-252180D01*
X266307Y-252763D01*
X264561Y-252180D01*
X263032Y-250430D01*
X262159Y-247805D01*
X261941Y-244888D01*
X262377Y-241097D01*
X263032Y-239054D01*
X264124Y-237013D01*
X265652Y-235555D01*
X267181Y-235263D01*
X268709Y-235846D01*
X269801Y-237305D01*
G01X279659Y-253346D02*
X287519Y-235263D01*
G01X296941Y-238180D02*
X298251Y-236430D01*
X299779Y-235555D01*
X301526Y-235263D01*
X303709Y-235846D01*
X305237Y-237305D01*
X305674Y-239054D01*
X305456Y-240805D01*
X304582Y-242263D01*
X300216Y-245180D01*
X298251Y-247221D01*
X296941Y-250139D01*
X296504Y-252763D01*
X305674D01*
G01X318589Y-235263D02*
X316842Y-235846D01*
X315532Y-237305D01*
X314659Y-239054D01*
X314004Y-241388D01*
X313786Y-244013D01*
X314004Y-246638D01*
X314659Y-248972D01*
X315532Y-250722D01*
X316842Y-252180D01*
X318589Y-252763D01*
X320335Y-252180D01*
X321646Y-250722D01*
X322519Y-248972D01*
X323174Y-246638D01*
X323392Y-244013D01*
X323174Y-241388D01*
X322519Y-239054D01*
X321646Y-237305D01*
X320335Y-235846D01*
X318589Y-235263D01*
G01X336089Y-252763D02*
Y-235263D01*
X333469Y-238763D01*
G01Y-252763D02*
X338709D01*
G01X349441Y-238180D02*
X350751Y-236430D01*
X352279Y-235555D01*
X354026Y-235263D01*
X356209Y-235846D01*
X357737Y-237305D01*
X358174Y-239054D01*
X357956Y-240805D01*
X357082Y-242263D01*
X352716Y-245180D01*
X350751Y-247221D01*
X349441Y-250139D01*
X349004Y-252763D01*
X358174D01*
G01X243786Y-207763D02*
Y-190263D01*
X248152D01*
X249899Y-191138D01*
X251209Y-192305D01*
X252301Y-194054D01*
X253174Y-196097D01*
X253392Y-199013D01*
X253174Y-201930D01*
X252301Y-203972D01*
X251209Y-205722D01*
X249899Y-206888D01*
X248152Y-207763D01*
X243786D01*
G01X270019D02*
Y-196097D01*
G01Y-198138D02*
X269146Y-196972D01*
X267835Y-196388D01*
X266307Y-196097D01*
X264779Y-196680D01*
X263469Y-197846D01*
X262595Y-199596D01*
X262159Y-201930D01*
X262595Y-204263D01*
X263469Y-206013D01*
X264779Y-207180D01*
X266307Y-207763D01*
X267835Y-207471D01*
X269146Y-206597D01*
X270019Y-205430D01*
G01X283589Y-190263D02*
Y-207763D01*
G01X280532Y-196097D02*
X286646D01*
G01X297814Y-199888D02*
X304801D01*
X304146Y-197846D01*
X303054Y-196680D01*
X301526Y-196097D01*
X299997Y-196388D01*
X298687Y-197263D01*
X297814Y-199305D01*
X297377Y-201055D01*
Y-202805D01*
X297814Y-204555D01*
X298906Y-206305D01*
X300216Y-207471D01*
X301744Y-207763D01*
X303272Y-207180D01*
X304801Y-205430D01*
G01X225700Y496800D02*
Y495770D01*
X221199Y491269D01*
Y463300D01*
X223600Y460899D01*
Y456200D01*
G01X226000Y458700D02*
Y461469D01*
X223300Y464169D01*
Y490400D01*
X228500Y495600D01*
Y498900D01*
G54D15*
X22980Y59055D03*
X30854D03*
X22980Y106299D03*
Y98425D03*
Y90551D03*
Y82677D03*
Y74803D03*
Y66929D03*
X30854Y106299D03*
Y98425D03*
Y90551D03*
Y82677D03*
Y74803D03*
Y66929D03*
X41142Y135669D03*
Y155669D03*
Y145669D03*
X26181Y537559D03*
Y527559D03*
Y517559D03*
X41142Y655669D03*
Y645669D03*
Y635669D03*
Y763780D03*
Y753780D03*
Y773780D03*
G54D25*
G01X84863Y229783D02*
Y232123D01*
X76072Y240914D01*
X75434Y241551D01*
X73542Y243443D01*
Y243476D01*
X72904Y244113D01*
Y244748D01*
X76692Y248536D01*
Y249172D01*
X76055Y249809D01*
X75419D01*
X71624Y246014D01*
X70988D01*
X70350Y246651D01*
Y247286D01*
X74146Y251082D01*
Y251718D01*
X73509Y252355D01*
X72873D01*
X69069Y248551D01*
X68433D01*
X67796Y249188D01*
Y249824D01*
X71600Y253628D01*
Y254264D01*
X70430Y255434D01*
X69794D01*
X66043Y251683D01*
X65407D01*
X64770Y252320D01*
Y252956D01*
X68521Y256707D01*
Y257343D01*
X67884Y257980D01*
X67248D01*
X63737Y254469D01*
X63101D01*
X62464Y255106D01*
Y255742D01*
X65975Y259253D01*
Y259889D01*
X57713Y268151D01*
X57077D01*
X53119Y264193D01*
X52483D01*
X51846Y264830D01*
Y265466D01*
X55804Y269424D01*
Y270060D01*
X55167Y270697D01*
X54531D01*
X50573Y266739D01*
X49937D01*
X49300Y267376D01*
Y268012D01*
X53258Y271970D01*
Y272606D01*
X52621Y273243D01*
X51985D01*
X48027Y269285D01*
X47391D01*
X46754Y269922D01*
Y270558D01*
X50712Y274516D01*
Y275152D01*
X5219Y320645D01*
Y424337D01*
X6750Y425868D01*
G01X14147Y438989D02*
X8589Y433431D01*
Y415411D01*
X8669Y415331D01*
Y413901D01*
X7240Y412472D01*
Y376963D01*
X7064Y376787D01*
Y324424D01*
X44657Y286831D01*
X78386D01*
X87971Y296416D01*
X111499D01*
X127444Y280471D01*
Y271904D01*
X131901Y267447D01*
Y267444D01*
G01X79189Y235119D02*
X61056Y253252D01*
X59252D01*
X58184Y254320D01*
Y256124D01*
X37470Y276838D01*
Y277474D01*
X40470Y280474D01*
Y281110D01*
X39833Y281747D01*
X39197D01*
X36197Y278747D01*
X35561D01*
X34924Y279384D01*
Y280020D01*
X37924Y283020D01*
Y283656D01*
X37287Y284293D01*
X36651D01*
X33651Y281293D01*
X33015D01*
X32378Y281930D01*
Y282566D01*
X35378Y285566D01*
Y286202D01*
X34741Y286839D01*
X34105D01*
X31105Y283839D01*
X30469D01*
X29832Y284476D01*
Y285112D01*
X32832Y288112D01*
Y288748D01*
X32195Y289385D01*
X31559D01*
X28559Y286385D01*
X27923D01*
X3306Y311002D01*
Y445331D01*
X7180Y449205D01*
G01X22980Y66929D02*
X26809Y63100D01*
X33959D01*
X48049Y77190D01*
Y82400D01*
X51816Y86167D01*
X55333D01*
X69074Y99908D01*
X89543D01*
X137467Y147832D01*
Y161860D01*
X219539Y243932D01*
Y295985D01*
X232046Y308492D01*
Y367432D01*
X214700Y384778D01*
Y397900D01*
X213588Y399012D01*
Y423567D01*
X207000Y430155D01*
Y451931D01*
X205231Y453700D01*
Y493890D01*
X213500Y502159D01*
Y503600D01*
G01X30854Y59055D02*
X32249D01*
X60200Y87006D01*
Y88700D01*
X69715Y98215D01*
X90184D01*
X139117Y147148D01*
Y161176D01*
X221189Y243248D01*
Y295301D01*
X233696Y307808D01*
Y368116D01*
X218078Y383734D01*
Y395622D01*
X217800Y395900D01*
G01X22980Y59055D02*
X26435Y55600D01*
X32500D01*
X70300Y93400D01*
X89434D01*
X140767Y144733D01*
Y160492D01*
X222839Y242564D01*
Y294617D01*
X235346Y307124D01*
Y368800D01*
X220100Y384046D01*
Y396500D01*
X218599Y398001D01*
Y412499D01*
X217083Y414015D01*
Y422406D01*
X208947Y430542D01*
Y443700D01*
G01X30854Y74803D02*
X33467D01*
X40505Y81841D01*
Y88139D01*
X62616Y110250D01*
X92450D01*
X132100Y149900D01*
Y163800D01*
X142248Y173948D01*
Y178251D01*
X143594Y179597D01*
X148202D01*
X214589Y245984D01*
Y298037D01*
X216987Y300435D01*
Y370053D01*
X195740Y391300D01*
Y427059D01*
X197900Y429219D01*
Y436513D01*
X200453Y439066D01*
G01X210223Y501477D02*
X201149Y492403D01*
Y456034D01*
X199815Y454700D01*
Y443087D01*
X196123Y439395D01*
Y429776D01*
X194090Y427743D01*
Y373729D01*
X204754Y363065D01*
Y238483D01*
X147585Y181314D01*
X142977D01*
X140598Y178935D01*
Y174698D01*
X129900Y164000D01*
Y150400D01*
X91400Y111900D01*
X61932D01*
X38855Y88823D01*
Y85155D01*
X32300Y78600D01*
X27057D01*
X22980Y82677D01*
G01Y74803D02*
X26683Y71100D01*
X34800D01*
X42155Y78455D01*
Y87455D01*
X57908Y103208D01*
X88175D01*
X134167Y149200D01*
Y163228D01*
X216239Y245300D01*
Y297353D01*
X218637Y299751D01*
Y371808D01*
X200345Y390100D01*
Y406082D01*
X201986Y407723D01*
Y433814D01*
X201400Y434400D01*
G01X30854Y66929D02*
X33129D01*
X46399Y80199D01*
Y83084D01*
X51132Y87817D01*
X54649D01*
X68390Y101558D01*
X88859D01*
X135817Y148516D01*
Y162544D01*
X217889Y244616D01*
Y296669D01*
X229263Y308043D01*
Y363999D01*
X206244Y387018D01*
Y395222D01*
X203636Y397830D01*
Y443402D01*
X202764Y444274D01*
G01X30854Y82677D02*
Y83156D01*
X61248Y113550D01*
X90450D01*
X128200Y151300D01*
Y169600D01*
X136175Y177575D01*
X136904D01*
X142360Y183031D01*
X146968D01*
X202800Y238863D01*
Y320300D01*
X193338Y329762D01*
Y372147D01*
X192440Y373045D01*
Y422885D01*
X190887Y424438D01*
G01X92682Y331571D02*
X30562D01*
X15998Y346135D01*
Y388732D01*
X13423Y391307D01*
Y408089D01*
X16382Y411048D01*
Y421240D01*
X17149Y422007D01*
Y423460D01*
X16211Y424398D01*
Y433772D01*
X17072Y434633D01*
Y435057D01*
G01X15424Y422722D02*
X14053Y421351D01*
Y420786D01*
X12340Y419073D01*
Y410269D01*
X11773Y409702D01*
Y386581D01*
X12718Y385636D01*
Y334589D01*
X14718Y332589D01*
Y331075D01*
X12718Y329075D01*
Y326358D01*
X24166Y314910D01*
Y311990D01*
X43542Y292614D01*
X66173D01*
X66623Y293064D01*
Y296563D01*
X67073Y297013D01*
X67973D01*
X68423Y296563D01*
Y293064D01*
X68873Y292614D01*
X69773D01*
X70223Y293064D01*
Y296563D01*
X70673Y297013D01*
X71573D01*
X72023Y296563D01*
Y293064D01*
X72473Y292614D01*
X73373D01*
X73823Y293064D01*
Y296563D01*
X74273Y297013D01*
X75173D01*
X75623Y296563D01*
Y293064D01*
X76073Y292614D01*
X77723D01*
X84825Y299716D01*
X113140D01*
X130744Y282112D01*
Y276432D01*
X134130Y273046D01*
Y271355D01*
X134529Y270956D01*
Y264470D01*
G01X19015Y426461D02*
Y421539D01*
X18032Y420556D01*
Y410364D01*
X15073Y407405D01*
Y393607D01*
X17648Y391032D01*
Y346847D01*
X31016Y333479D01*
X93355D01*
X94650Y332184D01*
Y330546D01*
X92004Y327900D01*
X84173D01*
X83723Y327450D01*
Y301816D01*
X84173Y301366D01*
X114272D01*
X133393Y282245D01*
Y276117D01*
X135780Y273730D01*
Y273080D01*
X137190Y271670D01*
Y266587D01*
G01X132163Y271041D02*
X129094Y274110D01*
Y281428D01*
X112456Y298066D01*
X85509D01*
X78407Y290964D01*
X75396D01*
X74946Y290514D01*
Y288931D01*
X74496Y288481D01*
X73596D01*
X73146Y288931D01*
Y290514D01*
X72696Y290964D01*
X71796D01*
X71346Y290514D01*
Y288931D01*
X70896Y288481D01*
X69996D01*
X69546Y288931D01*
Y290514D01*
X69096Y290964D01*
X68196D01*
X67746Y290514D01*
Y288931D01*
X67296Y288481D01*
X66396D01*
X65946Y288931D01*
Y290514D01*
X65496Y290964D01*
X64596D01*
X64146Y290514D01*
Y288931D01*
X63696Y288481D01*
X62796D01*
X62346Y288931D01*
Y290514D01*
X61896Y290964D01*
X50888D01*
X50438Y290514D01*
Y289684D01*
X49988Y289234D01*
X49088D01*
X48638Y289684D01*
Y290514D01*
X48188Y290964D01*
X47288D01*
X46838Y290514D01*
Y289684D01*
X46388Y289234D01*
X45488D01*
X45038Y289684D01*
Y290514D01*
X44588Y290964D01*
X42858D01*
X11068Y322754D01*
Y384952D01*
X10618Y385402D01*
X9340D01*
X8890Y385852D01*
Y411788D01*
X10319Y413217D01*
Y416015D01*
X10239Y416095D01*
Y432105D01*
X15872Y437738D01*
Y441916D01*
G01X135308Y276806D02*
Y283371D01*
X115663Y303016D01*
X85771D01*
X85373Y303414D01*
Y317732D01*
X85823Y318182D01*
X91223D01*
X91673Y318632D01*
Y319532D01*
X91223Y319982D01*
X85823D01*
X85373Y320432D01*
Y321332D01*
X85823Y321782D01*
X91223D01*
X91673Y322232D01*
Y323132D01*
X91223Y323582D01*
X85823D01*
X85373Y324032D01*
Y325682D01*
X85941Y326250D01*
X92689D01*
X96300Y329861D01*
Y332868D01*
X94039Y335129D01*
X32045D01*
X19298Y347876D01*
Y391716D01*
X16723Y394291D01*
Y405063D01*
X18448Y406788D01*
G01X23748Y436249D02*
Y434800D01*
X26082Y432466D01*
Y414577D01*
X25133Y413628D01*
Y398404D01*
X28276Y395261D01*
Y392261D01*
X25348Y389333D01*
Y369148D01*
X29137Y365360D01*
X32698Y361799D01*
Y341909D01*
X37828Y336779D01*
X94723D01*
X97950Y333552D01*
Y329177D01*
X93323Y324550D01*
Y317948D01*
X87818Y312443D01*
Y305986D01*
X89138Y304666D01*
X116456D01*
X137690Y283432D01*
Y273752D01*
G01X139784Y276432D02*
Y283794D01*
X117262Y306316D01*
X90712D01*
X89504Y307524D01*
Y311795D01*
X94973Y317264D01*
Y323866D01*
X99600Y328493D01*
Y334236D01*
X95407Y338429D01*
X90760D01*
X90310Y338879D01*
Y340200D01*
X89860Y340650D01*
X88960D01*
X88510Y340200D01*
Y338879D01*
X88060Y338429D01*
X87160D01*
X86710Y338879D01*
Y340200D01*
X86260Y340650D01*
X85360D01*
X84910Y340200D01*
Y338879D01*
X84460Y338429D01*
X83560D01*
X83110Y338879D01*
Y340200D01*
X82660Y340650D01*
X81760D01*
X81310Y340200D01*
Y338879D01*
X80860Y338429D01*
X79960D01*
X79510Y338879D01*
Y340200D01*
X79060Y340650D01*
X78160D01*
X77710Y340200D01*
Y338879D01*
X77260Y338429D01*
X76360D01*
X75910Y338879D01*
Y340200D01*
X75460Y340650D01*
X74560D01*
X74110Y340200D01*
Y338879D01*
X73660Y338429D01*
X72760D01*
X72310Y338879D01*
Y340200D01*
X71860Y340650D01*
X70960D01*
X70510Y340200D01*
Y338879D01*
X70060Y338429D01*
X69160D01*
X68710Y338879D01*
Y340200D01*
X68260Y340650D01*
X67360D01*
X66910Y340200D01*
Y338879D01*
X66460Y338429D01*
X65560D01*
X65110Y338879D01*
Y340200D01*
X64660Y340650D01*
X63760D01*
X63310Y340200D01*
Y338879D01*
X62860Y338429D01*
X61960D01*
X61510Y338879D01*
Y340200D01*
X61060Y340650D01*
X60160D01*
X59710Y340200D01*
Y338879D01*
X59260Y338429D01*
X58360D01*
X57910Y338879D01*
Y340200D01*
X57460Y340650D01*
X56560D01*
X56110Y340200D01*
Y338879D01*
X55660Y338429D01*
X54760D01*
X54310Y338879D01*
Y340200D01*
X53860Y340650D01*
X52960D01*
X52510Y340200D01*
Y338879D01*
X52060Y338429D01*
X51160D01*
X50710Y338879D01*
Y340200D01*
X50260Y340650D01*
X49360D01*
X48910Y340200D01*
Y338879D01*
X48460Y338429D01*
X47560D01*
X47110Y338879D01*
Y340200D01*
X46660Y340650D01*
X45760D01*
X45310Y340200D01*
Y338879D01*
X44860Y338429D01*
X43960D01*
X43510Y338879D01*
Y340200D01*
X43060Y340650D01*
X42160D01*
X41710Y340200D01*
Y338879D01*
X41260Y338429D01*
X39454D01*
X34348Y343535D01*
Y362483D01*
X29926Y366905D01*
Y395945D01*
X28697Y397174D01*
Y403837D01*
X26783Y405751D01*
Y412944D01*
X27732Y413893D01*
Y434279D01*
X26611Y435400D01*
Y441743D01*
G01X142241Y278783D02*
X141434Y279590D01*
Y284478D01*
X117946Y307966D01*
X95917D01*
X95467Y308416D01*
Y309634D01*
X95917Y310084D01*
X104220D01*
X104670Y310534D01*
Y311922D01*
X104220Y312372D01*
X94519D01*
X94069Y312822D01*
Y314025D01*
X94645Y314601D01*
X107216D01*
X107666Y315051D01*
Y316410D01*
X107216Y316860D01*
X97303D01*
X96853Y317310D01*
Y318210D01*
X97303Y318660D01*
X104864D01*
X105314Y319110D01*
Y320010D01*
X104864Y320460D01*
X97303D01*
X96853Y320910D01*
Y321810D01*
X97303Y322260D01*
X101642D01*
X102092Y322710D01*
Y334748D01*
X94323Y342517D01*
X40418D01*
X35998Y346937D01*
Y363167D01*
X31576Y367589D01*
Y396629D01*
X30347Y397858D01*
Y404521D01*
X28433Y406435D01*
Y412260D01*
X31957Y415784D01*
Y417271D01*
X31197Y418031D01*
Y429710D01*
X30513Y430394D01*
Y437850D01*
G01X160004Y233894D02*
X157068Y236830D01*
Y252453D01*
X144066Y265455D01*
Y284503D01*
X104184Y324385D01*
Y334990D01*
X94126Y345048D01*
X45175D01*
X38559Y351664D01*
Y364872D01*
X33226Y370205D01*
Y397313D01*
X31997Y398542D01*
Y405205D01*
X30083Y407119D01*
Y411575D01*
X33607Y415099D01*
Y417955D01*
X32847Y418715D01*
Y437956D01*
X28472Y442331D01*
Y447107D01*
G01X29700Y355000D02*
X28026D01*
X22800Y360226D01*
Y365508D01*
X21248Y367060D01*
Y393900D01*
X20500Y394648D01*
Y416841D01*
X21482Y417823D01*
Y419918D01*
X21000Y420400D01*
Y425160D01*
X21240Y425400D01*
Y430946D01*
X19373Y432813D01*
Y446473D01*
X23800Y450900D01*
Y459108D01*
X31267Y466575D01*
X36717D01*
X39572Y469430D01*
X50620D01*
X64450Y455600D01*
X72400D01*
X74523Y453477D01*
X74836D01*
G01X27284Y358500D02*
X24750Y361034D01*
Y366316D01*
X23198Y367868D01*
Y397102D01*
X22450Y397850D01*
Y414150D01*
X22100Y414500D01*
Y416200D01*
X23000Y417100D01*
Y420700D01*
X22600Y421100D01*
Y424242D01*
X23190Y424832D01*
Y431754D01*
X21323Y433621D01*
Y445664D01*
X25751Y450092D01*
Y451708D01*
X25750Y451709D01*
Y458300D01*
X32075Y464625D01*
X37525D01*
X40380Y467480D01*
X49812D01*
X66092Y451200D01*
X76200D01*
X77496Y449904D01*
X78754D01*
G01X36237Y441728D02*
Y419993D01*
X36907Y419323D01*
Y413276D01*
X37719Y412464D01*
Y387122D01*
X36794Y386197D01*
Y371305D01*
X53842Y354257D01*
X89795D01*
X107484Y336568D01*
Y326385D01*
X146932Y286937D01*
X149310D01*
X150755Y285492D01*
Y284773D01*
X152663Y282865D01*
Y272053D01*
G01X180991Y398678D02*
X180335Y398022D01*
Y397000D01*
X177735Y394400D01*
X171000D01*
X164123Y387523D01*
X83323D01*
X79600Y383800D01*
X69509D01*
X67527Y381818D01*
G01X185042Y286734D02*
X186623Y288315D01*
Y296318D01*
X186173Y296768D01*
X184911D01*
X184461Y297218D01*
Y298118D01*
X184911Y298568D01*
X186173D01*
X186623Y299018D01*
Y299918D01*
X186173Y300368D01*
X184911D01*
X184461Y300818D01*
Y301718D01*
X184911Y302168D01*
X186173D01*
X186623Y302618D01*
Y303518D01*
X186173Y303968D01*
X184911D01*
X184461Y304418D01*
Y305318D01*
X184911Y305768D01*
X186173D01*
X186623Y306218D01*
Y307118D01*
X186173Y307568D01*
X183100D01*
X182600Y307068D01*
Y302598D01*
X182102Y302100D01*
X181398D01*
X180900Y302598D01*
Y307068D01*
X180400Y307568D01*
X179500D01*
X179000Y307068D01*
Y302150D01*
X178500Y301650D01*
X177500D01*
X177000Y302150D01*
Y307068D01*
X176500Y307568D01*
X172810D01*
X168587Y311791D01*
X164700D01*
X152900Y323591D01*
Y338734D01*
X118802Y372832D01*
X71614D01*
X58463Y385983D01*
Y438162D01*
X59209Y438908D01*
G01X167051Y293752D02*
Y292949D01*
X168400Y291600D01*
X170510D01*
X171010Y292100D01*
Y304700D01*
X167219Y308491D01*
X163109D01*
X149600Y322000D01*
Y333400D01*
X114341Y368659D01*
X109358D01*
X108161Y369856D01*
X67615D01*
X51401Y386070D01*
Y418513D01*
X50394Y419520D01*
Y440090D01*
X51424Y441120D01*
X55187D01*
X55637Y441570D01*
Y443508D01*
X55187Y443958D01*
X51678D01*
X51228Y444408D01*
Y445308D01*
X51678Y445758D01*
X55187D01*
X55637Y446208D01*
Y447108D01*
X55187Y447558D01*
X51678D01*
X51228Y448008D01*
Y448908D01*
X51678Y449358D01*
X55187D01*
X55637Y449808D01*
Y450080D01*
X56087Y450530D01*
X56987D01*
X57437Y450080D01*
Y441412D01*
X57887Y440962D01*
X59634D01*
X60084Y441412D01*
Y450191D01*
X57610Y452665D01*
X57609D01*
X56447Y453828D01*
X50303D01*
X48896Y452421D01*
Y443839D01*
X46853Y441796D01*
G01X192284Y258847D02*
X190757Y260374D01*
Y261010D01*
X192203Y262457D01*
Y263093D01*
X191566Y263730D01*
X190930D01*
X189484Y262283D01*
X188848D01*
X188211Y262920D01*
Y263556D01*
X189657Y265003D01*
Y265639D01*
X189020Y266276D01*
X188384D01*
X186938Y264829D01*
X186302D01*
X185132Y265999D01*
Y266681D01*
X184494Y267319D01*
Y267925D01*
X127100Y325319D01*
Y333500D01*
X122657Y337943D01*
Y348357D01*
X122174Y348839D01*
X122173Y348841D01*
X108061Y362954D01*
X61101D01*
X46820Y377235D01*
Y388298D01*
X46451Y388667D01*
Y412377D01*
X47094Y413020D01*
Y415818D01*
X45444Y417468D01*
Y430981D01*
X43659Y432766D01*
G01X195698Y259749D02*
Y272574D01*
X194478Y273794D01*
X180960D01*
X128750Y326004D01*
Y334184D01*
X124307Y338627D01*
Y349042D01*
X108745Y364604D01*
X61785D01*
X48470Y377919D01*
Y388982D01*
X48101Y389351D01*
Y411693D01*
X48744Y412336D01*
Y416502D01*
X47094Y418152D01*
Y434067D01*
X43088Y438073D01*
G01X196365Y256414D02*
X192135D01*
X184271Y264278D01*
X182363D01*
X181295Y265346D01*
Y268790D01*
X129531Y320554D01*
X120317D01*
X112434Y328437D01*
Y338740D01*
X89870Y361304D01*
X53797D01*
X41744Y373357D01*
Y382674D01*
X45170Y386100D01*
Y387614D01*
X44801Y387983D01*
Y413061D01*
X45444Y413704D01*
Y415134D01*
X41857Y418721D01*
Y421375D01*
X41363Y421869D01*
Y452218D01*
X45486Y456341D01*
G01X42312Y463368D02*
X46461D01*
X46550Y463279D01*
X48199D01*
X60934Y450544D01*
Y427214D01*
X59313Y425593D01*
Y387451D01*
X72796Y373968D01*
X144143D01*
X172400Y345711D01*
Y324300D01*
X188273Y308427D01*
Y285674D01*
G01X37988Y438328D02*
X38063Y438253D01*
Y420501D01*
X38557Y420007D01*
Y413961D01*
X39369Y413149D01*
Y386438D01*
X38444Y385513D01*
Y371989D01*
X52639Y357794D01*
X88712D01*
X109134Y337372D01*
Y327069D01*
X118949Y317254D01*
X124556D01*
X132065Y309745D01*
Y304274D01*
X147002Y289337D01*
X156080D01*
X164364Y281053D01*
Y250357D01*
X168324Y246397D01*
G01X52476Y439395D02*
Y403067D01*
X52251Y402842D01*
Y386423D01*
X67968Y370706D01*
X118594D01*
X151250Y338050D01*
Y322691D01*
X163800Y310141D01*
X167903D01*
X173708Y304336D01*
Y295487D01*
X174878Y294317D01*
X175514D01*
X179958Y298762D01*
X180594D01*
X181232Y298124D01*
Y297488D01*
X176787Y293044D01*
Y292408D01*
X177424Y291771D01*
X178060D01*
X180276Y293987D01*
X180912D01*
X181549Y293350D01*
Y292714D01*
X179333Y290498D01*
Y289862D01*
X184286Y284909D01*
X184487D01*
X187118Y282278D01*
Y281963D01*
G01X167894Y243024D02*
X170149Y245279D01*
Y252155D01*
X166038Y256266D01*
Y281713D01*
X156744Y291007D01*
X147666D01*
X133715Y304958D01*
Y310429D01*
X125240Y318904D01*
X119633D01*
X110784Y327753D01*
Y338056D01*
X89343Y359497D01*
X53270D01*
X40094Y372673D01*
Y384828D01*
X41019Y385753D01*
Y413833D01*
X40207Y414645D01*
Y420691D01*
X39713Y421185D01*
Y443574D01*
X36841Y446446D01*
Y460938D01*
X37420Y461517D01*
G01X31517Y445328D02*
Y441620D01*
X34497Y438640D01*
Y419399D01*
X35257Y418639D01*
Y411849D01*
X34013Y410605D01*
Y403788D01*
X35447Y402354D01*
Y387185D01*
X35144Y386882D01*
Y370621D01*
X40209Y365556D01*
Y352348D01*
X45041Y347516D01*
X94202D01*
X105834Y335884D01*
Y325069D01*
X145716Y285187D01*
Y266712D01*
X162714Y249714D01*
Y244672D01*
X167760Y239626D01*
G01X163142Y294193D02*
Y297391D01*
X163592Y297841D01*
X168734D01*
X169184Y298291D01*
Y299191D01*
X168734Y299641D01*
X163592D01*
X163142Y300091D01*
Y300991D01*
X163592Y301441D01*
X168790D01*
X169240Y301891D01*
Y302791D01*
X168790Y303241D01*
X163592D01*
X163142Y303691D01*
Y304591D01*
X163592Y305041D01*
X166500D01*
X167000Y305541D01*
Y306341D01*
X166500Y306841D01*
X150247D01*
X130400Y326688D01*
Y334868D01*
X125957Y339311D01*
Y349726D01*
X106964Y368719D01*
X105314D01*
X104864Y368269D01*
Y366704D01*
X104414Y366254D01*
X103514D01*
X103064Y366704D01*
Y368269D01*
X102614Y368719D01*
X101714D01*
X101264Y368269D01*
Y366704D01*
X100814Y366254D01*
X99914D01*
X99464Y366704D01*
Y368269D01*
X99014Y368719D01*
X98114D01*
X97664Y368269D01*
Y366704D01*
X97214Y366254D01*
X96314D01*
X95864Y366704D01*
Y368269D01*
X95414Y368719D01*
X66775D01*
X66362Y369132D01*
X66005D01*
X50120Y385017D01*
Y389666D01*
X49751Y390035D01*
Y411009D01*
X50394Y411652D01*
Y417186D01*
X48744Y418836D01*
Y439164D01*
X48294Y439614D01*
X43987D01*
X43013Y440588D01*
Y443583D01*
X43463Y444033D01*
X46654D01*
X47104Y444483D01*
Y445383D01*
X46654Y445833D01*
X43463D01*
X43013Y446283D01*
Y447183D01*
X43463Y447633D01*
X46611D01*
X47061Y448083D01*
Y448983D01*
X46611Y449433D01*
X43463D01*
X43013Y449883D01*
Y451533D01*
X46096Y454616D01*
X46201D01*
X46398Y454813D01*
X48298D01*
G01X67244Y535455D02*
X68418D01*
X74552Y529321D01*
Y519609D01*
X87582Y506579D01*
X171216D01*
X185455Y492340D01*
Y457240D01*
X184951Y456736D01*
Y451332D01*
X180313Y446694D01*
G01X72677Y528615D02*
Y518617D01*
X86365Y504929D01*
X170532D01*
X183805Y491656D01*
Y457924D01*
X183215Y457334D01*
Y452856D01*
X176915Y446556D01*
G01X87263Y264658D02*
Y283064D01*
X95157Y290958D01*
X95202D01*
G01X87227Y242891D02*
X85438Y244680D01*
Y261138D01*
X87088Y262788D01*
Y264483D01*
X87263Y264658D01*
G01X90652Y265960D02*
Y264374D01*
X88738Y262460D01*
Y262104D01*
X87088Y260454D01*
Y247318D01*
X87698Y246708D01*
G01X98565Y290455D02*
X91047Y282937D01*
Y266625D01*
X90652Y266230D01*
Y265960D01*
G01X94051Y265872D02*
X92302Y264123D01*
Y263334D01*
X88738Y259770D01*
Y249787D01*
X91230Y247295D01*
Y247047D01*
G01X102107Y290439D02*
X102076D01*
X93321Y281684D01*
Y266602D01*
X94051Y265872D01*
G01X95146Y279609D02*
X95877Y278878D01*
Y263568D01*
X91819Y259510D01*
Y250396D01*
G01X98546Y279609D02*
X97527Y278590D01*
Y262884D01*
X94906Y260263D01*
Y252781D01*
X94793Y252668D01*
Y252595D01*
G01X104413Y278608D02*
X99177Y273372D01*
Y262200D01*
X98211Y261234D01*
Y252758D01*
G01X142933Y251431D02*
X139600D01*
X135674Y255357D01*
X132651D01*
G01X124933Y270414D02*
X126600D01*
X128742Y268272D01*
Y255795D01*
X133124Y251413D01*
X136427D01*
G01X124874Y273953D02*
X123249Y272328D01*
Y271312D01*
X123108Y271171D01*
Y269657D01*
X124699Y268066D01*
Y257504D01*
X134556Y247647D01*
X137809D01*
G01X116566Y254205D02*
X115416Y255355D01*
Y265679D01*
X114858Y266237D01*
Y270055D01*
X114229Y270684D01*
G01X119242Y252107D02*
Y254111D01*
X117066Y256287D01*
Y266363D01*
X116508Y266921D01*
Y271292D01*
X112042Y275758D01*
Y275903D01*
G01X117027Y278475D02*
X116394Y277842D01*
Y273740D01*
X118158Y271976D01*
Y267605D01*
X118716Y267047D01*
Y256971D01*
X121067Y254620D01*
Y250359D01*
X121685Y249741D01*
G01X121741Y246341D02*
X123510Y248110D01*
Y254511D01*
X120366Y257655D01*
Y267731D01*
X119808Y268289D01*
Y272908D01*
X118219Y274497D01*
G01X122572Y258147D02*
X122016Y258703D01*
Y268415D01*
X121458Y268973D01*
Y271855D01*
X121599Y271996D01*
Y274869D01*
G01X113558Y261260D02*
Y245380D01*
X111008Y242830D01*
G01X106504Y243329D02*
X105196D01*
X104124Y244401D01*
Y246813D01*
X104574Y247263D01*
X106367D01*
X106817Y247713D01*
Y248613D01*
X106367Y249063D01*
X104574D01*
X104124Y249513D01*
Y250413D01*
X104574Y250863D01*
X107494D01*
X107944Y251313D01*
Y252213D01*
X107494Y252663D01*
X104574D01*
X104124Y253113D01*
Y254013D01*
X104574Y254463D01*
X107266D01*
X107716Y254913D01*
Y255813D01*
X107266Y256263D01*
X104574D01*
X104124Y256713D01*
Y257546D01*
X104574Y257996D01*
X105931D01*
X106381Y258446D01*
Y259865D01*
G01D02*
X107002Y260486D01*
Y263274D01*
X106062Y264214D01*
Y275943D01*
X107750Y277631D01*
Y277953D01*
G01X103610Y268626D02*
Y260867D01*
X103003Y260260D01*
G01D02*
Y260026D01*
X103251Y259778D01*
Y259007D01*
X101686Y257442D01*
Y248440D01*
X102474Y247652D01*
Y246215D01*
X102240Y245981D01*
Y245922D01*
X101147Y244829D01*
Y243425D01*
X101597Y242975D01*
X102713D01*
G01X108652Y247260D02*
X109797Y248405D01*
Y264737D01*
X107887Y266647D01*
G01X101242Y265901D02*
Y265217D01*
X100827Y264802D01*
Y260212D01*
X100036Y259421D01*
Y247058D01*
X100415Y246679D01*
G01X105603Y291092D02*
X104317Y292378D01*
X99398D01*
X98948Y292828D01*
Y293837D01*
X99398Y294287D01*
X106800D01*
X108507Y292580D01*
Y289820D01*
X107021Y288334D01*
X102305D01*
X95034Y281063D01*
Y280063D01*
X95010Y280039D01*
Y279745D01*
X95146Y279609D01*
G01X110808Y291075D02*
X110157Y290424D01*
Y289136D01*
X107705Y286684D01*
X102989D01*
X101202Y284897D01*
Y284206D01*
X101652Y283756D01*
X104528D01*
X104978Y283306D01*
Y282297D01*
X104528Y281847D01*
X98790D01*
X98101Y281158D01*
Y280054D01*
X98546Y279609D01*
G01X114915Y290203D02*
X113560D01*
X111248Y287891D01*
Y287886D01*
X110591Y287229D01*
Y286002D01*
X111188Y285406D01*
Y284769D01*
X110459Y284040D01*
X109824D01*
X109288Y284576D01*
X109273D01*
X108897Y284953D01*
X108261D01*
X107553Y284246D01*
Y283611D01*
X109806Y281358D01*
X109821D01*
X111320Y279860D01*
Y279224D01*
X110612Y278516D01*
X109976D01*
X108516Y279975D01*
Y279980D01*
X107526Y280970D01*
X106775D01*
X104413Y278608D01*
G01X85721Y385798D02*
X164598D01*
X171000Y392200D01*
X179478D01*
X188978Y401700D01*
Y425111D01*
X194473Y430606D01*
Y442132D01*
X196803Y444462D01*
G01X85654Y659044D02*
X90800Y653898D01*
Y644800D01*
X185888Y549712D01*
X212203D01*
X221824Y540091D01*
Y522746D01*
X215978Y516900D01*
X207373D01*
X188755Y498282D01*
Y455872D01*
X188251Y455368D01*
Y440451D01*
X174500Y426700D01*
Y424100D01*
G01X83960Y632636D02*
X99464D01*
X184749Y547351D01*
X212230D01*
X220174Y539407D01*
Y523430D01*
X215405Y518661D01*
X206800D01*
X187105Y498966D01*
Y456556D01*
X186601Y456052D01*
Y448317D01*
X182060Y443776D01*
G01X177715Y397471D02*
Y397842D01*
X183301Y403428D01*
Y425716D01*
X182925Y426092D01*
Y430625D01*
X189523Y437223D01*
Y454306D01*
X190405Y455188D01*
Y497598D01*
X207521Y514714D01*
X218955D01*
X227294Y523053D01*
Y553515D01*
X206098Y574711D01*
Y628717D01*
X86915Y747900D01*
X84900D01*
G01X85000Y775900D02*
X85407D01*
X207748Y653559D01*
Y575395D01*
X228944Y554199D01*
Y522369D01*
X217449Y510874D01*
X208315D01*
X194841Y497400D01*
Y495886D01*
X192055Y493100D01*
Y454504D01*
X191173Y453622D01*
Y434373D01*
X184753Y427953D01*
X184750D01*
G01X273554Y386722D02*
Y173854D01*
X206138Y106438D01*
X204849D01*
G01X236973Y795418D02*
X236551D01*
X232066Y790933D01*
Y784466D01*
X210283Y762683D01*
Y575194D01*
X230594Y554883D01*
Y521685D01*
X217010Y508101D01*
X208700D01*
X197849Y497250D01*
Y457964D01*
X192823Y452938D01*
Y431290D01*
X187328Y425795D01*
Y405015D01*
X180991Y398678D01*
G01X203186Y451492D02*
X205350Y449328D01*
Y429471D01*
X211938Y422883D01*
Y396062D01*
X212500Y395500D01*
G01X206871Y397177D02*
X209956Y400262D01*
Y412179D01*
X210042Y412265D01*
G01X224664Y293860D02*
X252844Y322040D01*
Y371656D01*
X224200Y400300D01*
Y404965D01*
X221346Y407819D01*
Y414916D01*
X218733Y417529D01*
Y423412D01*
X210772Y431373D01*
Y431456D01*
G01X235169Y791455D02*
Y785169D01*
X211933Y761933D01*
Y575878D01*
X232244Y555567D01*
Y521001D01*
X217443Y506200D01*
X211770D01*
X199499Y493929D01*
Y456718D01*
X195400Y452619D01*
Y452051D01*
G01X240130Y789012D02*
Y787530D01*
X217165Y764565D01*
Y576831D01*
X233894Y560102D01*
Y520212D01*
X213583Y499901D01*
Y466983D01*
X208632Y462032D01*
Y457048D01*
G01X228949Y410741D02*
Y408751D01*
X230467Y407233D01*
X233830D01*
X265631Y375432D01*
Y217295D01*
X223948Y175612D01*
Y174292D01*
G01X219548Y174651D02*
X220229D01*
X263681Y218103D01*
Y374624D01*
X233022Y405283D01*
X229658D01*
X225421Y409520D01*
Y410908D01*
G01X255010Y367624D02*
Y242782D01*
X223129Y210901D01*
G01X232200Y492100D02*
Y463440D01*
X233375Y462265D01*
Y453717D01*
X226700Y447042D01*
Y412990D01*
X228949Y410741D01*
G01X225421Y410908D02*
Y411511D01*
X224750Y412182D01*
Y447850D01*
X231425Y454525D01*
Y461457D01*
X230250Y462632D01*
Y493980D01*
X231739Y495469D01*
G01X269840Y386256D02*
X277348Y393764D01*
X277362D01*
X339474Y455876D01*
X343876D01*
X347560Y459560D01*
Y462152D01*
X622154Y736746D01*
X743236D01*
X746669Y740179D01*
G01X730967Y759864D02*
X715704Y775127D01*
X629948D01*
X267710Y412889D01*
X266211D01*
X261300Y407978D01*
Y402355D01*
G01X275500Y415400D02*
X276772D01*
X308647Y447275D01*
X309657D01*
X620111Y757729D01*
X681377D01*
X681402Y757754D01*
G01X680480Y773302D02*
X630520D01*
X265444Y408226D01*
X264131D01*
X264124Y408219D01*
G01X258267Y408800D02*
X258734D01*
X265317Y415383D01*
X267870D01*
X634955Y782468D01*
X676408D01*
X678755Y784815D01*
G01X233400Y409700D02*
Y434100D01*
X235400Y436100D01*
X239100D01*
X255900Y452900D01*
X263766D01*
X268250Y457384D01*
Y460136D01*
X614397Y806283D01*
X682693D01*
G01X742663Y788885D02*
X733207Y798341D01*
X687095D01*
X677454Y788700D01*
X631207D01*
X307155Y464648D01*
X303328D01*
X292180Y453500D01*
X288300D01*
X285590Y450790D01*
Y446910D01*
X279120Y440440D01*
G01X276761Y443421D02*
X282290Y448950D01*
Y457608D01*
X291015Y466333D01*
X294633D01*
X620680Y792380D01*
X678737D01*
X686348Y799991D01*
X734783D01*
X739510Y795264D01*
G01X745230Y793211D02*
X736800Y801641D01*
X682084D01*
X680996Y800553D01*
X615669D01*
X277976Y462860D01*
Y449799D01*
X277575Y449398D01*
G01X742370Y799077D02*
X737244Y804203D01*
X614651D01*
X270714Y460266D01*
Y458323D01*
G01X747659Y796960D02*
X736511Y808108D01*
X613888D01*
X266600Y460820D01*
Y458417D01*
X263719Y455536D01*
G01X744790Y802781D02*
X735228Y812343D01*
X613455D01*
X259779Y458667D01*
Y456823D01*
G01X749593Y803991D02*
X739591Y813993D01*
X608311D01*
X312803Y518485D01*
Y514769D01*
X260322Y462288D01*
G01X747556Y808994D02*
X740907Y815643D01*
X607626D01*
X277051Y485068D01*
Y483949D01*
X258433Y465331D01*
X256852D01*
G01X749629Y812608D02*
X744944Y817293D01*
X606587D01*
X275401Y486107D01*
Y484633D01*
X260014Y469246D01*
X258221D01*
G01X676727Y790555D02*
X676523Y790351D01*
X621547D01*
X283940Y452744D01*
Y447877D01*
X257304Y421241D01*
X257184D01*
G01X271342Y440630D02*
X271388D01*
X280640Y449882D01*
Y460740D01*
X291100Y471200D01*
X296700D01*
X301915Y476415D01*
Y484465D01*
X611922Y794472D01*
X678246D01*
X679630Y795856D01*
G01X235600Y433300D02*
X239500D01*
X257200Y451000D01*
X265972D01*
X272539Y457567D01*
Y459757D01*
X615160Y802378D01*
X680239D01*
G01X684732Y810518D02*
X684726Y810512D01*
X613958D01*
X264842Y461396D01*
Y459303D01*
X264775Y459236D01*
G01X279789Y432846D02*
Y437624D01*
X284465Y442300D01*
X289500D01*
X292082Y444882D01*
Y449917D01*
X305163Y462998D01*
X307839D01*
X631388Y786547D01*
X667952D01*
X668387Y786112D01*
X669886D01*
G01X285565Y438912D02*
X288446D01*
X293732Y444198D01*
Y449233D01*
X305847Y461348D01*
X308523D01*
X631897Y784722D01*
X666516D01*
G01X250400Y473300D02*
Y473664D01*
X257687Y480951D01*
Y486301D01*
X597855Y826469D01*
X646342D01*
G01X260481Y473769D02*
X262203D01*
X273751Y485317D01*
Y487039D01*
X606581Y819869D01*
X653859D01*
X675856Y841866D01*
X679332D01*
G01X253214Y469048D02*
Y469083D01*
X260631Y476500D01*
X262600D01*
X272100Y486000D01*
Y487969D01*
X605760Y821629D01*
X649709D01*
X673062Y844982D01*
X681156D01*
G01X249845Y469508D02*
Y469545D01*
X603579Y823279D01*
X646359D01*
X671441Y848361D01*
X681542D01*
G01X324400Y570500D02*
Y567400D01*
X270500Y513500D01*
Y510900D01*
X259100Y499500D01*
X242500D01*
X235750Y492750D01*
Y468050D01*
X237200Y466600D01*
Y462900D01*
X235325Y461025D01*
Y452909D01*
X229291Y446875D01*
Y442509D01*
X229300Y442500D01*
G01X223671Y740896D02*
X222913Y740138D01*
Y580609D01*
X266441Y537081D01*
Y524300D01*
X268550Y522191D01*
Y511708D01*
X258767Y501925D01*
X242025D01*
X232200Y492100D01*
G01X231739Y495469D02*
X232569D01*
X240975Y503875D01*
X257959D01*
X266600Y512516D01*
Y521383D01*
X264491Y523492D01*
Y536273D01*
X220963Y579801D01*
Y739443D01*
X219590Y740816D01*
G01X721243Y850725D02*
X715760Y856208D01*
X621374D01*
X306000Y540834D01*
Y536948D01*
X258260Y489208D01*
X248286D01*
G01X242100Y489000D02*
Y492400D01*
X247550Y497850D01*
X259784D01*
X272151Y510217D01*
Y512133D01*
X623845Y863827D01*
X718263D01*
G01X223129Y764830D02*
Y760714D01*
X230263Y753580D01*
Y643856D01*
X281183Y592936D01*
G01X743653Y744114D02*
X618718D01*
X301437Y426833D01*
G01X741453Y748054D02*
X620022D01*
X304568Y432600D01*
X304200D01*
G01X738850Y751989D02*
X621623D01*
X309883Y440249D01*
X308553D01*
X300710Y432406D01*
X300603D01*
G01X734450Y755929D02*
X623229D01*
X309200Y441900D01*
X307516D01*
X297338Y431722D01*
Y429741D01*
X297238Y429641D01*
G01X667982Y739870D02*
X666837Y738725D01*
X620036D01*
X343910Y462599D01*
Y459250D01*
X342186Y457526D01*
X337854D01*
X304550Y424222D01*
G01X663575Y742289D02*
X661661Y740375D01*
X617698D01*
X300399Y423076D01*
X300291D01*
X300059Y422844D01*
G01X304000Y538500D02*
Y541250D01*
X624752Y862002D01*
X710727D01*
G01X308800Y540925D02*
Y541230D01*
X621953Y854383D01*
X678351D01*
G01X420575Y467336D02*
X425697Y462214D01*
Y192222D01*
X373496Y140021D01*
G01X668987Y731465D02*
Y632276D01*
X497279Y460568D01*
Y382551D01*
G01X719800Y525000D02*
X718750Y526050D01*
X708392D01*
X685271Y549171D01*
X650571D01*
X646400Y545000D01*
X637942D01*
X634249Y548693D01*
Y552851D01*
X632600Y554500D01*
Y555200D01*
G01X719866Y528656D02*
X719210Y528000D01*
X709200D01*
X686079Y551121D01*
X649571D01*
X645400Y546950D01*
X638750D01*
X636200Y549500D01*
Y555100D01*
G01X643100Y589900D02*
X692900Y639700D01*
X757600D01*
G01X727300Y273200D02*
X727400Y273300D01*
Y438300D01*
X762300Y473200D01*
Y490100D01*
X763000Y490800D01*
G54D16*
X29528Y19685D03*
X76772D03*
X108268Y905512D03*
X155512D03*
G54D17*
X53547Y322486D03*
Y302486D03*
X182681Y580832D03*
Y560832D03*
G54D18*
X109410Y796831D03*
Y876397D03*
X168465Y796831D03*
Y876397D03*
G54D19*
X286982Y828335D03*
X276982D03*
X286982Y818335D03*
X276982D03*
X356982Y828335D03*
X346982D03*
X336982D03*
X326982D03*
X316982D03*
X306982D03*
X296982D03*
X356982Y818335D03*
X346982D03*
X336982D03*
X326982D03*
X316982D03*
X306982D03*
X296982D03*
X366982Y828335D03*
Y818335D03*
M02*
